G04 ================== begin FILE IDENTIFICATION RECORD ==================*
G04 Layout Name:  15968-1a.brd*
G04 Film Name:    L3*
G04 File Format:  Gerber RS274X*
G04 File Origin:  Cadence Allegro 16.5-S058*
G04 Origin Date:  Fri Oct 14 10:25:50 2016*
G04 *
G04 Layer:  VIA CLASS/L3*
G04 Layer:  PIN/L3*
G04 Layer:  ETCH/L3*
G04 Layer:  DRAWING FORMAT/LAYER_PCB_STORY*
G04 Layer:  DRAWING FORMAT/LAYER_L3*
G04 *
G04 Offset:    (0.00 0.00)*
G04 Mirror:    No*
G04 Mode:      Positive*
G04 Rotation:  0*
G04 FullContactRelief:  No*
G04 UndefLineWidth:     6.00*
G04 ================== end FILE IDENTIFICATION RECORD ====================*
%FSLAX35Y35*MOIN*%
%IR0*IPPOS*OFA0.00000B0.00000*MIA0B0*SFA1.00000B1.00000*%
%ADD12C,.02*%
%ADD10C,.022*%
%ADD13C,.042*%
%ADD14C,.101*%
%ADD11C,.155*%
%ADD15C,.005*%
%ADD16C,.006*%
%ADD20C,.06004*%
%ADD18C,.04404*%
%ADD19C,.04604*%
%ADD21C,.06604*%
%ADD17C,.11004*%
%ADD23C,.12504*%
%ADD22C,.17904*%
G75*
%LPD*%
G75*
G36*
G01X77804Y-52600D02*
X75954Y-50750D01*
Y-854D01*
X72100Y3000D01*
X15600D01*
X15525Y3075D01*
X11375D01*
X3150Y11300D01*
Y83350D01*
X38000Y118200D01*
Y148284D01*
X26142Y160142D01*
Y161258D01*
X26100Y161300D01*
Y162700D01*
X32200Y168800D01*
X34400D01*
X50150Y153050D01*
X50200D01*
X58350Y144900D01*
X58400D01*
X58500Y144800D01*
Y141300D01*
X59700Y140100D01*
X60917D01*
X60951Y140087D01*
G03X63083Y140100I1049J2813D01*
G01X69500D01*
X70000Y139600D01*
Y136400D01*
X67200Y133600D01*
X50900D01*
X50150Y132850D01*
Y100950D01*
X26200Y77000D01*
Y75500D01*
X18000Y67300D01*
Y22500D01*
X24500Y16000D01*
X78500D01*
X92000Y2500D01*
Y-51250D01*
X90650Y-52600D01*
X77804D01*
G37*
G36*
G01X35800Y228600D02*
X32100Y224900D01*
Y182900D01*
X20100Y170900D01*
Y162600D01*
X35100Y147600D01*
Y123000D01*
X20700Y108600D01*
X6200D01*
X3001Y111799D01*
Y238051D01*
G02X3937Y238987I936J0D01*
G01X101000D01*
Y238900D01*
X103300Y236600D01*
Y231900D01*
X100000Y228600D01*
X35800D01*
G37*
G36*
G01X316619Y-34231D02*
X318389Y-38503D01*
X318379Y-38524D01*
X318855Y-39668D01*
X319260Y-41961D01*
Y-43240D01*
X318700Y-43800D01*
Y-44641D01*
G03Y-48287I1321J-1823D01*
G01Y-48800D01*
X318800Y-48900D01*
X400300D01*
X402400Y-51000D01*
Y-62500D01*
X401900Y-63000D01*
X191600D01*
X190300Y-61700D01*
Y-52600D01*
G03X174700I-7800J-260D01*
G01Y-62600D01*
X174300Y-63000D01*
X96200D01*
X94600Y-61400D01*
Y-7100D01*
X99900Y-1800D01*
X140300D01*
X170600Y28500D01*
Y37148D01*
G03Y41252I-800J2052D01*
G01Y88600D01*
X172129Y90129D01*
G02X172780Y90002I283J-283D01*
G03X176815Y92178I2119J899D01*
G02X177147Y92800I333J222D01*
G01X182222D01*
Y75274D01*
X181846Y74899D01*
X181760Y74901D01*
G03X183901Y72760I-60J-2201D01*
G01X183899Y72846D01*
X185124Y74072D01*
Y92800D01*
X202600D01*
X204600Y90800D01*
Y47600D01*
X163900Y6900D01*
X161321D01*
G03X159516Y6917I-921J-2000D01*
G01X159478Y6900D01*
X159300D01*
X158998Y6598D01*
X158991Y6592D01*
G03X158708Y6309I1409J-1692D01*
G01X158702Y6302D01*
X157800Y5400D01*
Y3900D01*
X158700Y3000D01*
X159286D01*
X159331Y2975D01*
G03X161513Y3000I1069J1925D01*
G01X166300D01*
X213400Y50100D01*
Y65800D01*
X215700Y68100D01*
X234500D01*
X235100Y67500D01*
X299900Y-23000D01*
X312438Y-30238D01*
X315156Y-32141D01*
X316619Y-34231D01*
G37*
G36*
G01X103100Y1800D02*
X101400Y3500D01*
Y18010D01*
G03Y18190I-2200J90D01*
G01Y20200D01*
X93900Y27700D01*
Y61500D01*
X97762Y65362D01*
X97867Y65341D01*
G03X100459Y67933I433J2159D01*
G01X100438Y68038D01*
X101200Y68800D01*
Y73200D01*
X115200Y87200D01*
Y93470D01*
X115354Y93506D01*
G03Y97794I-504J2144D01*
G01X115200Y97830D01*
Y99000D01*
X116700Y100500D01*
X139400D01*
X149350Y90550D01*
Y87590D01*
G03Y87410I2200J-90D01*
G01Y84768D01*
G03Y82232I1800J-1268D01*
G01Y77036D01*
G02X148827Y76655I-400J0D01*
G03Y70945I-927J-2855D01*
G02X149350Y70564I123J-381D01*
G01Y29150D01*
X154800Y23700D01*
Y21300D01*
X154200Y20700D01*
X147200D01*
X145700Y19200D01*
X145500D01*
Y6800D01*
X140500Y1800D01*
X103100D01*
G37*
G36*
G01X104315Y149285D02*
X104306Y149192D01*
G03X105700Y146948I2194J-192D01*
G01Y139819D01*
G02X105287Y139419I-400J0D01*
G03X103167Y138020I-69J-2201D01*
G02X102596Y137818I-373J145D01*
G03X103551Y135106I-1096J-1910D01*
G02X104122Y135308I373J-145D01*
G03X105287Y135017I1096J1910D01*
G02X105700Y134617I13J-400D01*
G01Y131300D01*
X105800Y131200D01*
Y130900D01*
X114000Y122700D01*
Y114400D01*
X111800Y112200D01*
X108200D01*
X108000Y112400D01*
X103500D01*
X99400Y108300D01*
Y81700D01*
X99350Y81650D01*
Y76800D01*
X94750Y72200D01*
X85900D01*
X83652Y74448D01*
Y86201D01*
X83300Y86553D01*
Y86700D01*
X73952Y96048D01*
Y117552D01*
X77500Y121100D01*
X84600D01*
X89300Y125800D01*
Y128100D01*
X87872Y129528D01*
X87885Y129625D01*
G03X85425Y132085I-2185J275D01*
G01X85328Y132072D01*
X83600Y133800D01*
Y145600D01*
X76900Y152300D01*
Y200905D01*
G03X77390Y201406I-1309J1771D01*
G02X78044I327J-230D01*
G03Y203946I1799J1270D01*
G02X77390I-327J230D01*
G03X73911Y204099I-1799J-1270D01*
G02X73628Y204076I-153J129D01*
G03X70343Y201217I-1428J-1676D01*
G01X70429Y201082D01*
X69748Y200401D01*
Y171699D01*
X70437Y171010D01*
G02X70361Y170385I-283J-283D01*
G03X71839Y166324I1138J-1885D01*
G02X72300Y165929I61J-395D01*
G01Y154400D01*
X66900Y149000D01*
X65206D01*
G02X64821Y149508I0J400D01*
G03X60579I-2121J592D01*
G02X60194Y149000I-385J-108D01*
G01X59400D01*
X55100Y153300D01*
Y162900D01*
X55200Y163000D01*
Y177494D01*
G02X55708Y177879I400J0D01*
G03Y182121I592J2121D01*
G02X55200Y182506I-108J385D01*
G01Y201300D01*
X54900Y201600D01*
Y206600D01*
X60173Y211873D01*
X60222Y211888D01*
G03X61331Y212639I-622J2112D01*
G02X62008Y212562I315J-247D01*
G03X65481Y211870I1992J938D01*
G02X66019I269J-296D01*
G03X69694Y213317I1481J1630D01*
G01X69710Y213500D01*
X99000D01*
X115100Y197400D01*
X153800D01*
X164300Y207900D01*
X168000D01*
X169200Y206700D01*
Y196755D01*
X156949Y184504D01*
X156912D01*
X156910Y184502D01*
X111098D01*
X101800Y193800D01*
X97268D01*
G03X94100Y190887I-1268J-1800D01*
G01Y179800D01*
X97828Y176072D01*
X97815Y175975D01*
G03X100275Y173515I2185J-275D01*
G01X100372Y173528D01*
X100900Y173000D01*
Y152700D01*
X104315Y149285D01*
G37*
G36*
G01X135644Y216117D02*
Y213949D01*
G02X135133Y213565I-400J0D01*
G03X134634Y207119I-920J-3171D01*
G02X134967Y206439I51J-397D01*
G01X129458Y200930D01*
X115370D01*
X98700Y217600D01*
X53100D01*
X45800Y210300D01*
X37700D01*
X34900Y213100D01*
Y218800D01*
X41900Y225800D01*
X100400D01*
X113587Y238987D01*
X123706D01*
G02X123990Y238306I0J-400D01*
G03X128686I2348J-2322D01*
G02X128970Y238987I284J281D01*
G01X131581D01*
G02X131865Y238306I0J-400D01*
G03X135133Y232813I2348J-2322D01*
G02X135644Y232429I111J-384D01*
G01Y230261D01*
G03Y225957I2504J-2152D01*
G01Y220421D01*
G03Y216117I2504J-2152D01*
G37*
G36*
G01X134500Y115900D02*
X118600Y131800D01*
Y154000D01*
X132500Y167900D01*
X160600D01*
X162700Y165800D01*
Y154500D01*
X157553Y149353D01*
G02X156906Y149471I-283J283D01*
G03X155951Y145523I-3008J-1362D01*
G02X156600Y145210I249J-313D01*
G01Y144989D01*
X156548Y144937D01*
Y141208D01*
G02X155905Y140891I-400J0D01*
G03Y135647I-2007J-2622D01*
G02X156541Y135406I243J-317D01*
G01X156600Y135347D01*
Y133457D01*
G03X155634Y127931I1233J-3063D01*
G02X155650Y127350I-267J-298D01*
G01X144200Y115900D01*
X134500D01*
G37*
G36*
G01X141044Y199954D02*
X138011Y202987D01*
Y204125D01*
X140001Y206115D01*
Y207099D01*
G02X140583Y207455I400J0D01*
G03Y213333I1505J2939D01*
G02X140001Y213689I-182J356D01*
G01Y215536D01*
G03Y221002I-1853J2733D01*
G01Y225376D01*
G03Y230842I-1853J2733D01*
G01Y232689D01*
G02X140583Y233045I400J0D01*
G03X144436Y238306I1505J2939D01*
G02X144720Y238987I284J281D01*
G01X147331D01*
G02X147615Y238306I0J-400D01*
G03X152311I2348J-2322D01*
G02X152595Y238987I284J281D01*
G01X155201D01*
G02X155485Y238306I0J-400D01*
G03X158143Y232697I2348J-2322D01*
G02X158580Y232298I37J-398D01*
G01Y228951D01*
X158574Y228926D01*
G03Y227292I3199J-817D01*
G01X158580Y227267D01*
Y226969D01*
X156748Y225137D01*
Y221044D01*
G02X156084Y220744I-400J0D01*
G03X156451Y216175I-2186J-2475D01*
G02X157043Y216204I309J-254D01*
G01X158968Y214279D01*
G02X158593Y213607I-283J-283D01*
G03X161046Y211154I-760J-3213D01*
G02X161718Y211529I389J92D01*
G01X161992Y211255D01*
Y207546D01*
X154400Y199954D01*
X141044D01*
G37*
G36*
G01X445800Y-63000D02*
X443700Y-60900D01*
Y-41000D01*
X441100Y-38400D01*
X409000D01*
X404300Y-33700D01*
X380393Y522D01*
G02X380641Y1143I328J229D01*
G03X378326Y4456I-441J2157D01*
G02X377658Y4437I-340J210D01*
G01X374400Y9100D01*
X365800Y17700D01*
Y52447D01*
X381196Y67844D01*
G02X381790Y67813I283J-283D01*
G03X384887Y70910I1710J1387D01*
G02X384856Y71504I252J311D01*
G01X386152Y72799D01*
Y73152D01*
X386600Y73600D01*
Y78040D01*
X400378Y91818D01*
G02X400944I283J-283D01*
G03X401230Y91577I1557J1557D01*
G02Y90923I-230J-327D01*
G03X403770I1270J-1799D01*
G02Y91577I230J327D01*
G03X404058Y94932I-1270J1799D01*
G02Y95498I283J283D01*
G01X424660Y116100D01*
X463200D01*
X472098Y107202D01*
Y56798D01*
X469200Y53900D01*
X463063D01*
G03X459600Y51080I-1550J-1633D01*
G01Y49945D01*
G03X459572Y47616I1913J-1188D01*
G01X459600Y47569D01*
Y47500D01*
X459783Y47317D01*
X459789Y47310D01*
G03X460065Y47034I1724J1448D01*
G01X460072Y47028D01*
X461700Y45400D01*
Y31464D01*
X457736Y27500D01*
X454200D01*
X453600Y28100D01*
Y36401D01*
X456202Y39002D01*
Y40555D01*
G03Y40645I-2202J45D01*
G01Y44498D01*
X456200Y44499D01*
Y45900D01*
X451700Y50400D01*
Y75500D01*
X448200Y79000D01*
X439500D01*
X432254Y86246D01*
Y90804D01*
X432100Y90958D01*
Y91600D01*
X429800Y93900D01*
X419800D01*
X411000Y85100D01*
Y76900D01*
X402400Y68300D01*
X399468D01*
X399440Y68308D01*
G03X398170I-635J-2108D01*
G01X398142Y68300D01*
X395600D01*
X395588Y68288D01*
X395500Y68292D01*
G03X393700Y64700I-94J-2200D01*
G01Y44900D01*
X388623Y39823D01*
X388514Y39849D01*
G03X386075Y36647I-508J-2143D01*
G01X386100Y36602D01*
Y36000D01*
X387800Y34300D01*
X389500D01*
G03X393306Y35058I1700J1400D01*
G01X393350Y35200D01*
X400300D01*
X406819Y28681D01*
X406734Y28546D01*
G03X407330Y25577I1866J-1170D01*
G02Y24923I-230J-327D01*
G03X410208Y21620I1270J-1799D01*
G02X410900Y21346I292J-274D01*
G01Y17400D01*
X414300Y14000D01*
X436100D01*
X436697Y13403D01*
X436699Y13325D01*
G03X438825Y11199I2201J75D01*
G01X438903Y11197D01*
X439400Y10700D01*
Y9164D01*
X439348Y9113D01*
Y-20513D01*
X439400Y-20564D01*
Y-20900D01*
X444900Y-26400D01*
X445236D01*
X446187Y-27352D01*
X522352D01*
X525064Y-30063D01*
Y-33736D01*
X522900Y-35900D01*
Y-37172D01*
X522887Y-37206D01*
G03Y-38794I2107J-794D01*
G01X522900Y-38828D01*
Y-40500D01*
X523900Y-41500D01*
X531800D01*
X533300Y-40000D01*
Y-35800D01*
X533200Y-35700D01*
X533000D01*
X530966Y-33666D01*
Y-27402D01*
X530250Y-26686D01*
Y-26500D01*
X530064D01*
X525013Y-21448D01*
X524848D01*
X524300Y-20900D01*
X487400D01*
X486400Y-19900D01*
Y-7900D01*
X510700Y16400D01*
Y196700D01*
X512300Y198300D01*
X515800D01*
X516450Y197650D01*
X527150D01*
X529000Y195800D01*
Y183200D01*
X533000Y179200D01*
X548700D01*
X554700Y185200D01*
Y187215D01*
G02X555456Y187397I400J0D01*
G03X567283Y190071I5568J2864D01*
G01X567286Y190168D01*
Y190266D01*
Y190356D01*
X567283Y190451D01*
G03X555456Y193125I-6259J-190D01*
G02X554700Y193307I-356J182D01*
G01Y203751D01*
G02X555456Y203933I400J0D01*
G03X567283Y206607I5568J2864D01*
G01X567286Y206704D01*
Y206802D01*
Y206892D01*
X567283Y206987D01*
G03X555456Y209661I-6259J-190D01*
G02X554700Y209843I-356J182D01*
G01Y231400D01*
X551600Y234500D01*
X517200D01*
X508500Y225800D01*
X474400D01*
X468500Y219900D01*
Y215400D01*
X467500Y214400D01*
X465300D01*
X462800Y216900D01*
Y236800D01*
X464987Y238987D01*
X602308D01*
G02X602968Y238713I-2J-936D01*
G01X612473Y229208D01*
G02X612747Y228548I-662J-662D01*
G01Y163248D01*
G02X611811Y162312I-936J0D01*
G01X562598D01*
G03X555660Y155374I0J-6938D01*
G01Y9504D01*
G02X555386Y8843I-936J1D01*
G01X549819Y3275D01*
G02X549159Y3001I-662J662D01*
G01X544016D01*
G03X537078Y-3937I0J-6938D01*
G01Y-47100D01*
X537000D01*
Y-61500D01*
X535500Y-63000D01*
X445800D01*
G37*
G36*
G01X415700Y15900D02*
X412292Y19308D01*
Y26392D01*
X410724Y27960D01*
X410709Y28008D01*
G03X409232Y29485I-2109J-632D01*
G01X409184Y29500D01*
X405110Y33573D01*
G02X405256Y34232I283J283D01*
G03X402432Y37056I-756J2068D01*
G02X401773Y36910I-376J137D01*
G01X401025Y37658D01*
Y44187D01*
G02X401224Y44387I200J0D01*
G03Y48791I-13J2202D01*
G02X401025Y48991I1J200D01*
G01Y65074D01*
X407084Y71133D01*
X407086Y71135D01*
G03X407165Y71214I-1517J1596D01*
G01X407167Y71216D01*
X412748Y76797D01*
Y84929D01*
X419913Y92094D01*
X429265D01*
X431053Y90306D01*
Y84516D01*
X438319Y77250D01*
X447969D01*
X449956Y75263D01*
Y49044D01*
X455000Y44000D01*
Y39500D01*
X452200Y36700D01*
Y25400D01*
X442700Y15900D01*
X415700D01*
G37*
G36*
G01X474100Y221200D02*
X475600Y222700D01*
X505900D01*
X507800Y220800D01*
Y17400D01*
X473100Y-17300D01*
X449700D01*
X448450Y-16050D01*
Y4800D01*
X474100Y30450D01*
Y221200D01*
G37*
G36*
G01X535300Y181600D02*
X531650Y185250D01*
Y198750D01*
X531350Y199050D01*
X531383Y199163D01*
G03X526391Y202136I-2883J837D01*
G02X526109I-141J142D01*
G03X521598Y201800I-2109J-2136D01*
G01X517000D01*
X516900Y201700D01*
X516800D01*
X516300Y202200D01*
Y206200D01*
X515300Y207200D01*
Y228900D01*
X518000Y231600D01*
X548900D01*
X549000Y231500D01*
X550300D01*
X552200Y229600D01*
Y187700D01*
X546100Y181600D01*
X535300D01*
G37*
%LPC*%
G75*
G36*
G01X113289Y-35056D02*
G03X113230Y-35603I259J-305D01*
G02X109536Y-38351I-1830J-1397D01*
G03X108899Y-38336I-324J-234D01*
G02X105611Y-35144I-1799J1436D01*
G03X105670Y-34597I-259J305D01*
G02X109364Y-31849I1830J1397D01*
G03X110001Y-31864I324J234D01*
G02X113289Y-35056I1799J-1436D01*
G37*
G36*
G01X112758Y-50881D02*
G03X112729Y-51473I254J-309D01*
G02X109236Y-54451I-1630J-1626D01*
G03X108599Y-54436I-324J-234D01*
G02X105342Y-51219I-1799J1435D01*
G03X105371Y-50627I-254J309D01*
G02X108864Y-47649I1630J1626D01*
G03X109501Y-47664I324J234D01*
G02X112758Y-50881I1799J-1435D01*
G37*
G36*
G01X109523Y9765D02*
G03X108967Y9753I-272J-293D01*
G02X108895Y12917I-1567J1547D01*
G03X109451Y12929I272J293D01*
G02X109523Y9765I1567J-1547D01*
G37*
G36*
G01X126047Y90780D02*
G02X123837Y90829I-1147J-1880D01*
G03X123853Y91520I-193J350D01*
G02X126063Y91471I1147J1880D01*
G03X126047Y90780I193J-350D01*
G37*
G36*
G01X136584Y63945D02*
G02X135339Y61124I816J-2045D01*
G03X134816Y61355I-375J-140D01*
G02X132280Y62026I-816J2045D01*
G03X131573Y61841I-312J-250D01*
G02X131120Y63574I-2173J358D01*
G03X131827Y63759I312J250D01*
G02X136061Y64176I2173J-359D01*
G03X136584Y63945I375J140D01*
G37*
G36*
G01X552646Y174472D02*
G03Y173818I230J-327D01*
G02X550106I-1270J-1799D01*
G03Y174472I-230J327D01*
G02X552646I1270J1799D01*
G37*
G36*
G01X455760Y103525D02*
G03X455221I-270J-295D01*
G02Y106777I-1485J1626D01*
G03X455760I269J295D01*
G02Y103525I1485J-1626D01*
G37*
G36*
G01X453007Y90234D02*
G03Y89695I295J-270D01*
G02X449755I-1626J-1485D01*
G03Y90234I-295J270D01*
G02X453007I1626J1485D01*
G37*
G36*
G01X418502Y37097D02*
G03X418702Y36897I200J0D01*
G02X416503Y34698I3J-2202D01*
G03X416303Y34898I-200J0D01*
G02X418502Y37097I-3J2202D01*
G37*
G36*
G01X426964Y51436D02*
G02X425292I-836J-1248D01*
G03Y52100I-223J332D01*
G02X425116Y54458I836J1248D01*
G03X425102Y55060I-270J295D01*
G02X424967Y55188I964J1152D01*
G03X424365Y55168I-292J-273D01*
G02X422081Y55120I-1162J951D01*
G03X421475Y55110I-299J-266D01*
G02X421443Y57071I-1153J962D01*
G03X422049Y57081I299J266D01*
G02X424300Y57144I1153J-962D01*
G03X424902Y57164I292J273D01*
G02X425082Y57349I1163J-951D01*
G03X425092Y57944I-262J302D01*
G02X425138Y60189I1021J1102D01*
G03X425108Y60820I-260J304D01*
G02X426946Y60907I863J1230D01*
G03X426976Y60276I260J-304D01*
G02X427096Y57910I-863J-1230D01*
G03X427086Y57315I262J-302D01*
G02X427270Y57109I-1023J-1099D01*
G03X427899Y57093I321J239D01*
G02X430250Y57047I1157J-958D01*
G03X430888Y57050I318J243D01*
G02X430897Y55239I1203J-900D01*
G03X430259Y55236I-318J-243D01*
G02X427851Y55239I-1203J899D01*
G03X427222Y55255I-321J-239D01*
G02X427077Y55103I-1157J958D01*
G03X427091Y54501I270J-295D01*
G02X426964Y52100I-963J-1153D01*
G03Y51436I223J-332D01*
G37*
G54D20*
X87900Y94500D03*
X520970Y192569D03*
G54D18*
X199400Y81400D03*
X233700Y54400D03*
X104500Y56200D03*
X121801Y16999D03*
X117200Y65750D03*
X116900Y59450D03*
X132600Y39900D03*
X124100Y78900D03*
X137900Y49400D03*
X93900Y95300D03*
X98900Y126800D03*
X83500Y189000D03*
X380500Y13200D03*
X383600Y59618D03*
X383400Y46600D03*
X380200Y25800D03*
X372400Y41100D03*
X433900Y11000D03*
X439000Y87700D03*
X520500Y154500D03*
X525000Y158000D03*
X517900Y103300D03*
X423500Y34200D03*
X409026Y61211D03*
X418650Y22850D03*
X431382Y35283D03*
X439418Y26110D03*
X429850Y22950D03*
G54D19*
X78000Y99900D03*
Y105800D03*
X428500Y107700D03*
X424200Y103800D03*
X432100D03*
G54D21*
X122403Y228109D03*
X130278D03*
X122403Y218269D03*
X126338Y210394D03*
X130278Y218269D03*
X122403Y148109D03*
X126338Y155984D03*
X130278Y148109D03*
X134213Y155984D03*
X138148Y148109D03*
X142088Y155984D03*
X146023Y148109D03*
X149963Y155984D03*
X157833D03*
X122403Y138269D03*
X126338Y130394D03*
X130278Y138269D03*
X134213Y130394D03*
X138148Y138269D03*
X142088Y130394D03*
X146023Y138269D03*
X149963Y130394D03*
X146023Y228109D03*
X153898D03*
X146023Y218269D03*
X149963Y210394D03*
G54D17*
X14794Y226306D03*
X542107Y17432D03*
X585785Y228866D03*
G54D23*
X539370Y190256D03*
Y206792D03*
G54D22*
X542913Y128150D03*
%LPD*%
G75*
G54D10*
X25700Y89200D03*
X27207Y85293D03*
X24400Y81900D03*
X22300Y85000D03*
X21800Y78600D03*
X21600Y74000D03*
X28200Y160400D03*
X95906Y-53300D03*
X84619Y-27663D03*
X89467Y-47981D03*
X84671Y-44973D03*
X79444Y-46817D03*
X90546Y-41425D03*
X90332Y-30191D03*
X85442Y-39927D03*
X79444Y-41282D03*
X90400Y-36500D03*
X85231Y-34026D03*
X79035Y-30696D03*
X79103Y-35748D03*
X107800Y4300D03*
X33200Y98700D03*
X30600Y88100D03*
X33700Y91400D03*
X29400Y92300D03*
X32800Y95000D03*
X102000Y40300D03*
X103000Y28300D03*
X105800Y40200D03*
X107000Y28300D03*
X96000Y80100D03*
X97800Y76800D03*
X93000Y73300D03*
X93800Y77000D03*
X89800Y76700D03*
X32400Y160600D03*
X29200Y164000D03*
X33100Y164800D03*
X36000Y161800D03*
X31000Y156900D03*
X44200Y212200D03*
X39200Y212100D03*
X44400Y217400D03*
X39300D03*
X111600Y4100D03*
X115500Y4000D03*
X119300Y3800D03*
X123000D03*
X127000Y3900D03*
X130800Y4000D03*
X131266Y85081D03*
X135025Y85092D03*
X138722Y85144D03*
X131666Y78581D03*
X135425Y78592D03*
X139122Y78644D03*
X109600Y40000D03*
X110800Y28100D03*
X138922Y94844D03*
X135225Y94792D03*
X131466Y94781D03*
X135100Y161900D03*
X155600Y166300D03*
X151700D03*
X134900Y165700D03*
X146165Y120044D03*
X140552Y117907D03*
X136626Y118116D03*
X142500Y203900D03*
X145300Y201100D03*
X148314Y203751D03*
X162100Y193800D03*
X165700Y195000D03*
X421405Y90902D03*
X418437Y87727D03*
X423690Y87875D03*
X453500Y-9800D03*
X449900Y-9700D03*
X453400Y-13500D03*
X449800D03*
X453500Y-5700D03*
X449900D03*
X453600Y-2000D03*
X450000Y-1900D03*
X460535Y76560D03*
X456662Y76376D03*
X495500Y219600D03*
Y210500D03*
X495400Y215300D03*
X500200Y219500D03*
X504800Y219600D03*
X504500Y210600D03*
X500200Y210400D03*
X504700Y215300D03*
X500100Y215200D03*
X540500Y219500D03*
X532200Y219300D03*
X527000Y219500D03*
X519900D03*
G54D11*
X15748Y128150D03*
X542913D03*
G54D12*
G01X-84798Y-164972D02*
Y-244972D01*
G01D02*
X1172402D01*
G01X-88798Y-148972D02*
G02I-12000J0D01*
G01X-93948D02*
G02I-6850J0D01*
G01X-100798Y-164972D02*
Y-132972D01*
G01X-84798Y-148972D02*
X-116798D01*
G01X-84798Y-164972D02*
X1172402D01*
G01X-84798Y-200472D02*
X1172402D01*
G01X64400Y152700D02*
X66100Y151000D01*
G01X56650Y164000D02*
X56400Y164250D01*
G01X149963Y126892D02*
Y130394D01*
G01D02*
Y133896D01*
G01X146461Y130394D02*
X149963D01*
G01D02*
X153465D01*
G01X157833Y152482D02*
Y155984D01*
G01D02*
Y159486D01*
G01X154331Y155984D02*
X157833D01*
G01D02*
X161335D01*
G01X153898Y144607D02*
Y148109D01*
G01D02*
Y151611D01*
G01X150396Y148109D02*
X153898D01*
G01X130278Y214767D02*
Y218269D01*
G01D02*
Y221771D01*
G01X126776Y218269D02*
X130278D01*
G01D02*
X133780D01*
G01X126338Y206892D02*
Y210394D01*
G01D02*
Y213896D01*
G01X122836Y210394D02*
X126338D01*
G01D02*
X129840D01*
G01X122403Y214767D02*
Y218269D01*
G01D02*
Y221771D01*
G01X118901Y218269D02*
X122403D01*
G01D02*
X125905D01*
G01X130278Y224607D02*
Y228109D01*
G01D02*
Y231611D01*
G01X126776Y228109D02*
X130278D01*
G01D02*
X133780D01*
G01X126338Y232482D02*
Y235984D01*
G01X122836D02*
X126338D01*
G01D02*
X129840D01*
G01X149963Y206892D02*
Y210394D01*
G01D02*
Y213896D01*
G01X146461Y210394D02*
X149963D01*
G01D02*
X153465D01*
G01X157833Y232482D02*
Y235984D01*
G01X154331D02*
X157833D01*
G01X153898Y224607D02*
Y228109D01*
G01D02*
Y231611D01*
G01X150396Y228109D02*
X153898D01*
G01D02*
X157400D01*
G01X172300Y192800D02*
X174400D01*
X175800Y194200D01*
X183000D01*
X191600Y185600D01*
G01X384902Y-164972D02*
Y-244972D01*
G01X522402Y-164972D02*
Y-244972D01*
G01X542913Y118998D02*
Y128150D01*
G01D02*
Y137302D01*
G01X533761Y128150D02*
X542913D01*
G01D02*
X552065D01*
G01X539370Y200340D02*
Y206792D01*
G01D02*
Y213244D01*
G01X532918Y206792D02*
X539370D01*
G01D02*
X545822D01*
G01X539370Y183804D02*
Y190256D01*
G01D02*
Y196708D01*
G01X532918Y190256D02*
X539370D01*
G01D02*
X545822D01*
G01X637402Y-164972D02*
Y-244972D01*
G01X804902Y-164972D02*
Y-244972D01*
G01X974902Y-164972D02*
Y-244972D01*
G01X1172402Y-164972D02*
Y-244972D01*
G01X1200402Y-148972D02*
G02I-12000J0D01*
G01X1195252D02*
G02I-6850J0D01*
G01X1188402Y-164972D02*
Y-132972D01*
G01X1204402Y-148972D02*
X1172402D01*
X6487Y175762D03*
Y165762D03*
X14947Y175971D03*
Y165971D03*
X22700Y190800D03*
X26300D03*
X26600Y201000D03*
X23000D03*
X6487Y235762D03*
X25453Y235870D03*
X15453D03*
X6487Y225762D03*
Y215762D03*
Y205762D03*
Y195762D03*
Y185762D03*
X14947Y195971D03*
Y185971D03*
X87250Y100650D03*
X88000Y65200D03*
X68800Y139000D03*
X59400Y151000D03*
X56400Y164250D03*
X67750Y160700D03*
X66100Y151000D03*
X98900Y172350D03*
X92400Y163100D03*
X80000Y158900D03*
X80400Y167200D03*
X102202Y131798D03*
X101500Y139900D03*
X105500Y109500D03*
X98400Y233100D03*
X35453Y235870D03*
X45453D03*
X55453D03*
X65453D03*
X75453D03*
X84400Y232900D03*
X89600D03*
X94900Y233000D03*
X56500Y202900D03*
X100500Y209300D03*
X96000Y192000D03*
X72200Y202400D03*
X161100Y13600D03*
X126800Y-53409D03*
X135182D03*
X144631D03*
X154080D03*
X163529D03*
X172977D03*
X116900Y-35400D03*
X146600Y3400D03*
X159450Y8750D03*
X160400Y4900D03*
X148300Y16700D03*
X147878Y13326D03*
X182000Y66700D03*
X174400Y32500D03*
X176300Y45200D03*
X153300Y22300D03*
X161400Y58700D03*
X154300Y56400D03*
X110781Y87200D03*
X181700Y72700D03*
X161694Y55106D03*
X111800Y113700D03*
X181400Y124500D03*
X172300Y192800D03*
X164200Y205100D03*
X173300Y204969D03*
X240100Y20900D03*
X221900Y5100D03*
X235600Y5300D03*
X247200Y5400D03*
X195200Y5700D03*
X191875Y-53409D03*
X201324D03*
X210773D03*
X220221D03*
X229670D03*
X239119D03*
X248568D03*
X258017D03*
X267466D03*
X252300Y22200D03*
X255900Y35000D03*
X246500Y47900D03*
X200500Y31500D03*
X216300Y46700D03*
X226600Y21400D03*
X198300Y73200D03*
X196400Y91600D03*
X193900Y51600D03*
X202800Y50200D03*
X218900Y65600D03*
X198900Y21200D03*
X230300Y45100D03*
X233800Y66000D03*
X199900Y161600D03*
X192200Y166700D03*
X195900Y162100D03*
X191600Y185600D03*
X319070Y-41541D03*
X276914Y-53409D03*
X286363D03*
X295812D03*
X305261D03*
X314710D03*
X324158D03*
X333607D03*
X343056D03*
X324021Y-46464D03*
X334221D03*
X344421D03*
X320021D03*
X330221D03*
X340421D03*
X329242Y-36479D03*
X339442D03*
X325242D03*
X335442D03*
X345642D03*
X343524Y36971D03*
X346000Y34640D03*
X346150Y84800D03*
X348200Y169900D03*
X332000Y192200D03*
X329400Y195900D03*
X334794Y195294D03*
X423852Y4375D03*
X420252Y-36925D03*
X410052Y-36825D03*
X380500Y17100D03*
X352505Y-53409D03*
X361954D03*
X371403D03*
X380851D03*
X390300D03*
X399815Y-52741D03*
X415100Y3400D03*
X380200Y6800D03*
X354621Y-46464D03*
X364821D03*
X375021D03*
X385221D03*
X395421D03*
X350621D03*
X360821D03*
X371021D03*
X381221D03*
X391421D03*
X349642Y-36479D03*
X359842D03*
X370042D03*
X380242D03*
X390442D03*
X400642D03*
X355842D03*
X366042D03*
X376242D03*
X386442D03*
X396642D03*
X405500Y29200D03*
X383300Y50700D03*
X383500Y65800D03*
X388000Y41600D03*
X394500Y34000D03*
X380300Y21600D03*
X405800Y21100D03*
Y94200D03*
X405600Y87500D03*
X405569Y72731D03*
X383600Y55532D03*
X373300Y35400D03*
X384000Y41600D03*
X391600Y29400D03*
X349701Y64199D03*
X353100Y63900D03*
X359023Y47177D03*
X355370Y37411D03*
X355300Y81400D03*
X349700Y56000D03*
X349000Y28300D03*
X404500Y47769D03*
X409400Y69800D03*
X423500Y37800D03*
X412000Y29900D03*
X356700Y86600D03*
X353098Y55882D03*
X350300Y31800D03*
X352138Y50729D03*
X351500Y36100D03*
X355536Y50589D03*
X352700Y40000D03*
X355399Y47191D03*
X355300Y33900D03*
X391200Y35700D03*
X398805Y66200D03*
X388006Y37706D03*
X395406Y66092D03*
X436752Y4175D03*
X498052Y-625D03*
X490200Y-6400D03*
X488652Y-18225D03*
X496352Y-19025D03*
X432452Y-36225D03*
X447252Y-47725D03*
X445252Y-37225D03*
X455701Y-53425D03*
X502945D03*
X493496D03*
X484047D03*
X474598D03*
X465149D03*
X446252D03*
X428600Y16900D03*
X469300Y87600D03*
X459652Y31575D03*
X458100Y47300D03*
Y53700D03*
X448200Y93000D03*
X448369Y86631D03*
X457400Y41800D03*
X468588Y55981D03*
X437300Y91100D03*
X454085Y63272D03*
X452496Y70099D03*
X454500Y29300D03*
X435287Y25646D03*
X441688Y74914D03*
X449400Y26433D03*
X454000Y40600D03*
X461513Y48758D03*
Y52267D03*
X452888Y108444D03*
X457097Y108548D03*
X466361Y230936D03*
X467506Y226106D03*
X502000Y229400D03*
X466010Y216328D03*
X492961Y227336D03*
X480761Y227936D03*
X505961Y236936D03*
X488161Y236336D03*
X479761D03*
X499761D03*
X455700Y205800D03*
X528590Y-12237D03*
Y2763D03*
X532137Y7890D03*
X532691Y-17725D03*
X531600Y-31800D03*
X523300Y-32100D03*
X531291Y-53425D03*
X521842D03*
X512393D03*
X524994Y-38000D03*
X530994D03*
X534737Y40290D03*
X534337Y52790D03*
X534637Y74290D03*
Y92590D03*
X532778Y21738D03*
X512000Y158400D03*
X511900Y174400D03*
Y142700D03*
X521900Y179500D03*
X548200Y169900D03*
X548300Y178100D03*
X578337Y166890D03*
X577748Y181113D03*
X529000Y158500D03*
X521600Y158400D03*
X524200Y181600D03*
X519700Y181900D03*
X521900Y184000D03*
X545300Y236800D03*
X529500Y236400D03*
X519761Y236336D03*
X537200Y236400D03*
X559761Y236336D03*
X579761D03*
X577748Y211113D03*
X578337Y226890D03*
X577748Y191113D03*
Y201113D03*
X593337Y166890D03*
Y176890D03*
X608337Y166890D03*
Y176890D03*
X599761Y236336D03*
X593337Y206890D03*
Y216890D03*
Y226890D03*
Y186890D03*
Y196890D03*
X608337Y206890D03*
Y216890D03*
Y226890D03*
Y186890D03*
Y196890D03*
G54D13*
X153898Y148109D03*
X157833Y155984D03*
X161773Y148109D03*
X149963Y130394D03*
X161773Y138269D03*
X126338Y235984D03*
X130278Y228109D03*
X153898D03*
X157833Y235984D03*
X161773Y228109D03*
X189333Y235984D03*
X122403Y218269D03*
X126338Y210394D03*
X130278Y218269D03*
X149963Y210394D03*
X181458D03*
X185393Y218269D03*
X193268Y228109D03*
X209018D03*
X212953Y235984D03*
X224763Y228109D03*
X228703Y235984D03*
X240513Y228109D03*
X244448Y235984D03*
X264133Y228109D03*
X268073Y235984D03*
X201143Y218269D03*
X205078Y210394D03*
X216888Y218269D03*
X220828Y210394D03*
X232638Y218269D03*
X236573Y210394D03*
X256258Y218269D03*
X260198Y210394D03*
X279883Y228109D03*
X283818Y235984D03*
X295628Y228109D03*
X299568Y235984D03*
X311378Y228109D03*
X315313Y235984D03*
X272008Y218269D03*
X275943Y210394D03*
X287758Y218269D03*
X291693Y210394D03*
X303503Y218269D03*
X307443Y210394D03*
X445238Y218269D03*
G54D14*
X539370Y190256D03*
Y206792D03*
G54D15*
G01X72200Y202400D02*
Y200800D01*
X71200Y199800D01*
Y172300D01*
X74100Y169400D01*
Y151600D01*
X75050Y150650D01*
Y123150D01*
X72500Y120600D01*
Y95300D01*
X82200Y85600D01*
Y71000D01*
X88000Y65200D01*
G01X161773Y228109D02*
X158200Y224536D01*
Y217100D01*
X163600Y211700D01*
X167000D01*
X171779Y206921D01*
X173689D01*
X174143Y206743D01*
X175150Y205736D01*
Y202050D01*
X174600Y201500D01*
Y198263D01*
X158089Y181752D01*
X158052D01*
X158050Y181750D01*
X154850D01*
X150100Y177000D01*
X104173D01*
X102400Y175227D01*
Y153600D01*
X104598Y151402D01*
X106715D01*
X108350Y149767D01*
Y148233D01*
X108326Y148209D01*
Y134774D01*
X109200Y133900D01*
Y133471D01*
X154500Y88171D01*
Y56600D01*
X154300Y56400D01*
G01X110781Y87200D02*
X110573D01*
X108966Y88807D01*
Y104034D01*
X105500Y107500D01*
Y109500D01*
G01X192200Y166700D02*
X187529D01*
X180179Y174050D01*
X107921D01*
X105299Y171428D01*
Y156872D01*
X111200Y150971D01*
Y134300D01*
X156500Y89000D01*
Y19729D01*
X152907Y16136D01*
X148964D01*
X148400Y16700D01*
X148300D01*
G01X173300Y204969D02*
Y198802D01*
X157550Y183052D01*
X157513D01*
X157511Y183050D01*
X110150D01*
X101200Y192000D01*
X96000D01*
G01X160400Y4900D02*
X164300D01*
X208600Y49200D01*
Y90600D01*
X193600Y105600D01*
Y132900D01*
X197000Y136300D01*
Y149900D01*
X200900Y153800D01*
Y160600D01*
X199900Y161600D01*
G01X195900Y162100D02*
X194400Y163600D01*
X187800D01*
X179350Y172050D01*
X108750D01*
X107300Y170600D01*
Y158500D01*
X109500Y156300D01*
Y155500D01*
X113200Y151800D01*
Y135129D01*
X158500Y89829D01*
Y18900D01*
X153736Y14136D01*
X148688D01*
X147878Y13326D01*
G01X161400Y58700D02*
X163650Y60950D01*
Y130350D01*
X158000Y136000D01*
Y144336D01*
X161773Y148109D01*
G01X181400Y124500D02*
Y122900D01*
X183673Y120627D01*
Y74673D01*
X181700Y72700D01*
G01X161773Y138269D02*
Y136227D01*
X166900Y131100D01*
Y60312D01*
X161694Y55106D01*
G01X185393Y218269D02*
X183906Y215292D01*
G03X184130Y214621I448J-223D01*
G01X184131D01*
X184577Y214399D01*
G02X186038Y210872I-3527J-3527D01*
G01Y209608D01*
X186629Y208494D01*
X201764Y184257D01*
X201846Y184125D01*
X209585Y158341D01*
Y156554D01*
G02X207645Y151870I-6624J0D01*
G01X207317Y151543D01*
G03X205701Y147640I3903J-3902D01*
G01Y139145D01*
G03X207814Y134044I7214J0D01*
G01X208342Y133516D01*
G02X209591Y130500I-3017J-3016D01*
G01X210068Y126607D01*
Y126234D01*
X223703Y91720D01*
X300124Y-17427D01*
G03X300247Y-17550I410J287D01*
G01X317362Y-29533D01*
G02X317767Y-29939I-948J-1351D01*
G01X319517Y-32439D01*
G02X319690Y-32754I-1351J-947D01*
G01X321914Y-38124D01*
X321930Y-38130D01*
X322118Y-38581D01*
X322661Y-41663D01*
Y-44653D01*
G03X324021Y-46464I1967J61D01*
G01X320021D02*
G03X321511Y-44688I-250J1722D01*
G01Y-41764D01*
X321029Y-39032D01*
X320842Y-38583D01*
X320851Y-38564D01*
X318627Y-33195D01*
G03X318575Y-33099I-462J-188D01*
G01X316824Y-30598D01*
X316823D01*
G03X316702Y-30475I-411J-284D01*
G01X299587Y-18492D01*
G02X299182Y-18087I947J1352D01*
G01X222683Y91171D01*
X208918Y126015D01*
Y126536D01*
X208441Y130429D01*
Y130500D01*
G03X207528Y132702I-3115J-1D01*
G01X207000Y133230D01*
G02X204551Y139144I5916J5914D01*
G01Y147640D01*
G02X206504Y152357I6669J1D01*
G01X206669Y152523D01*
X206832Y152685D01*
G03X208434Y156554I-3871J3869D01*
G01X208435Y156553D01*
Y158172D01*
X200788Y183647D01*
X200357Y184338D01*
X190165Y200658D01*
X189283Y200862D01*
X188489Y202135D01*
X188693Y203016D01*
X187898Y204289D01*
X187016Y204493D01*
X186222Y205765D01*
X186426Y206647D01*
X185631Y207919D01*
X184888Y209322D01*
Y210871D01*
G03X183884Y213458I-3837J-1D01*
G01X183619Y213591D01*
X183615Y213593D01*
X183614D01*
G03X182944Y213369I-223J-447D01*
G01X181458Y210394D01*
G01X205078D02*
X203589Y213370D01*
G03X202918Y213593I-447J-224D01*
G01X202917D01*
X202508Y213388D01*
X202507D01*
X202469Y213369D01*
G03X201540Y211124I2246J-2244D01*
G01Y206300D01*
X202144Y203557D01*
X203001Y202326D01*
X203892Y202166D01*
X204749Y200935D01*
X204589Y200044D01*
X205446Y198813D01*
X206337Y198653D01*
X207194Y197422D01*
X207034Y196531D01*
X207891Y195300D01*
X208782Y195141D01*
X209639Y193909D01*
X209479Y193019D01*
X219300Y175200D01*
X224845Y158430D01*
X224905Y158220D01*
X224906Y158216D01*
X225332Y156722D01*
G02X223395Y151870I-6622J-169D01*
G01X223067Y151543D01*
G03X221451Y147640I3903J-3902D01*
G01Y139145D01*
G03X223564Y134044I7214J0D01*
G01X224092Y133516D01*
G02X225341Y130500I-3017J-3016D01*
G01Y128540D01*
X239963Y89633D01*
X240533Y87042D01*
X241728Y80265D01*
X305912Y-11398D01*
X329146Y-27667D01*
X332190Y-32013D01*
X332915Y-36118D01*
G02X332932Y-36318I-1133J-197D01*
G01Y-37883D01*
X332593Y-39940D01*
X332861Y-41893D01*
Y-44046D01*
G03X333609Y-45852I2554J0D01*
G01X334221Y-46464D01*
G01X344421D02*
G02X343061Y-44653I607J1872D01*
G01Y-41920D01*
X342833Y-39380D01*
X342843Y-39293D01*
X343132Y-37887D01*
Y-33876D01*
X342927Y-32706D01*
X336222Y-23134D01*
X311861Y-6077D01*
X259515Y68683D01*
X254400Y77900D01*
X242700Y114800D01*
X241086Y128540D01*
Y130500D01*
G03X239837Y133516I-4266J0D01*
G01X239309Y134044D01*
G02X237196Y139145I5101J5101D01*
G01Y147640D01*
G02X238812Y151543I5519J1D01*
G01X239140Y151870D01*
G03X241080Y156554I-4684J4684D01*
G01Y158203D01*
X236100Y175500D01*
X236069Y175609D01*
X230142Y187031D01*
X229600Y187500D01*
X221500Y194600D01*
X221123Y196052D01*
X221581Y196832D01*
X221204Y198284D01*
X220424Y198743D01*
X220047Y200194D01*
X220505Y200975D01*
X220128Y202427D01*
X219348Y202885D01*
X218971Y204337D01*
X219429Y205117D01*
X219052Y206569D01*
X218272Y207028D01*
X217338Y210623D01*
X217289Y211122D01*
X217288Y211123D01*
X217291D01*
X217290Y211124D01*
G02X218220Y213369I3175J0D01*
G01X218667Y213593D01*
X218668D01*
G02X219339Y213370I224J-447D01*
G01X220828Y210394D01*
G01X201143Y218269D02*
X202627Y215294D01*
G02X202404Y214623I-447J-224D01*
G01X202403D01*
X202022Y214432D01*
X201801Y214321D01*
G03X200390Y211125I2914J-3196D01*
G03Y211123I4326J-1D01*
G01Y206174D01*
X201069Y203087D01*
X201200Y202900D01*
X208496Y192417D01*
X218241Y174738D01*
X223745Y158091D01*
X223797Y157908D01*
X223799Y157900D01*
X223800D01*
X224184Y156554D01*
G02X222582Y152685I-5473J0D01*
G01X222419Y152523D01*
X222254Y152357D01*
G03X220301Y147640I4716J-4716D01*
G01Y139144D01*
G03X222750Y133230I8365J0D01*
G01X223278Y132702D01*
G02X224190Y130500I-2202J-2202D01*
G01Y129270D01*
X224191Y128965D01*
Y128331D01*
X238857Y89305D01*
X239404Y86818D01*
X240639Y79814D01*
X305086Y-12224D01*
X328320Y-28493D01*
X331101Y-32464D01*
X331781Y-36315D01*
X331782Y-36316D01*
Y-37788D01*
X331429Y-39924D01*
X331711Y-41972D01*
Y-44120D01*
G02X331107Y-45578I-2062J0D01*
G01X330221Y-46464D01*
G01X340421D02*
G03X341911Y-44688I-313J1776D01*
G01Y-41972D01*
X341677Y-39369D01*
X341705Y-39112D01*
X341981Y-37770D01*
X341982D01*
Y-33976D01*
X341838Y-33157D01*
X335396Y-23960D01*
X311035Y-6903D01*
X258426Y68232D01*
X258510Y68124D01*
X253338Y77442D01*
X241570Y114557D01*
X239936Y128472D01*
Y128965D01*
X239935Y129270D01*
Y130500D01*
G03X239023Y132702I-3114J0D01*
G01X238495Y133230D01*
G02X236046Y139144I5916J5914D01*
G01Y147640D01*
G02X237999Y152357I6669J1D01*
G01X238164Y152523D01*
X238327Y152685D01*
G03X239929Y156554I-3871J3869D01*
G01X239930Y156553D01*
Y158040D01*
X234995Y175181D01*
X229223Y186305D01*
X228844Y186632D01*
X220475Y193968D01*
X220476D01*
X216202Y210421D01*
X216193Y210510D01*
X216144Y211009D01*
X216143Y211010D01*
X216142D01*
X216141Y211011D01*
G02X216140Y211124I4324J95D01*
G02X217551Y214321I4325J1D01*
G01X217772Y214432D01*
X218153Y214623D01*
X218154D01*
G03X218377Y215294I-224J447D01*
G01X216888Y218269D01*
G01X193268Y228109D02*
X191782Y231085D01*
G03X191111Y231309I-447J-223D01*
G01X191110D01*
X190662Y231085D01*
G03X189865Y229161I1924J-1924D01*
G01Y226032D01*
X190629Y222237D01*
X190429Y220534D01*
X190214Y218786D01*
X190203Y218734D01*
G03X191227Y215248I3705J-805D01*
G01X192083Y214392D01*
G02X194009Y209742I-4650J-4650D01*
G01X194010Y209741D01*
X194008D01*
Y209727D01*
X194310Y205220D01*
X194692Y204061D01*
X195513Y202806D01*
X196399Y202621D01*
X197221Y201366D01*
X197036Y200480D01*
X197858Y199225D01*
X198743Y199040D01*
X199565Y197785D01*
X199380Y196899D01*
X200202Y195644D01*
X201088Y195459D01*
X201909Y194204D01*
X201724Y193318D01*
X213147Y175865D01*
X213219Y175754D01*
X214301Y172795D01*
X217460Y158217D01*
Y156554D01*
G02X215520Y151870I-6624J0D01*
G01X215192Y151543D01*
G03X213576Y147640I3903J-3902D01*
G01Y139145D01*
G03X215689Y134044I7214J0D01*
G01X216217Y133516D01*
G02X217466Y130500I-3017J-3016D01*
G01Y128540D01*
X217723Y127088D01*
X232547Y86727D01*
X303121Y-14065D01*
G03X303244Y-14188I410J287D01*
G01X324595Y-29150D01*
X326100Y-30700D01*
X326192Y-30795D01*
X327852Y-33545D01*
X327882Y-34673D01*
G03X329242Y-36479I1966J66D01*
G01X339442D02*
G02X338082Y-34668I607J1872D01*
G01Y-34103D01*
X337891Y-33013D01*
X332715Y-25622D01*
X309283Y-9214D01*
X250513Y74719D01*
X233216Y128408D01*
Y130500D01*
G03X231967Y133516I-4266J0D01*
G01X231439Y134044D01*
G02X229326Y139145I5101J5101D01*
G01Y147640D01*
G02X230942Y151543I5519J1D01*
G01X231270Y151870D01*
G03X233210Y156554I-4684J4684D01*
G01Y158203D01*
X229700Y168900D01*
X228204Y173186D01*
X226314Y177170D01*
X224413Y181175D01*
X220959Y186066D01*
X209791Y209457D01*
Y211675D01*
G02X210301Y212906I1741J0D01*
G01X212405Y215011D01*
G03X213650Y218019I-3002J3004D01*
G01Y228468D01*
G03X212140Y232113I-5155J0D01*
G01X211693Y232337D01*
X211692D01*
G02X211469Y233008I224J447D01*
G01X212953Y235984D01*
G01X228703D02*
X227219Y233008D01*
G03X227442Y232337I447J-224D01*
G01X227443D01*
X227890Y232113D01*
G02X229400Y228468I-3645J-3645D01*
G02X229025Y222761I-43614J0D01*
G01Y218318D01*
G02X228511Y216195I-4230J-100D01*
G01X228134Y215502D01*
G02X227851Y215124I-1449J790D01*
G01X226338Y213611D01*
G03X225619Y211874I1739J-1737D01*
G01Y208800D01*
X229912Y201770D01*
X234437Y194361D01*
X238962Y186931D01*
X248968Y157729D01*
X248955Y156554D01*
G02X247015Y151870I-6624J0D01*
G01X246687Y151543D01*
G03X245071Y147640I3903J-3902D01*
G01Y139145D01*
G03X247184Y134044I7214J0D01*
G01X247712Y133516D01*
G02X248961Y130500I-3017J-3016D01*
G01Y128540D01*
X251418Y112531D01*
X268078Y63604D01*
X315165Y-3645D01*
X339580Y-20740D01*
X347945Y-32686D01*
X348265Y-34504D01*
X348282Y-34668D01*
G03X349642Y-36479I1967J61D01*
G01X325242D02*
G03X326732Y-34711I-250J1722D01*
G01X326710Y-33879D01*
X325275Y-31502D01*
X323845Y-30030D01*
X302584Y-15130D01*
G02X302179Y-14725I947J1352D01*
G01X231519Y86190D01*
X216608Y126787D01*
X216316Y128439D01*
Y128965D01*
X216315Y129270D01*
Y130500D01*
G03X215403Y132702I-3114J0D01*
G01X214875Y133230D01*
G02X212426Y139144I5916J5914D01*
G01Y147640D01*
G02X214379Y152357I6669J1D01*
G01X214544Y152523D01*
X214707Y152685D01*
G03X216309Y156554I-3871J3869D01*
G01X216310Y156553D01*
Y158093D01*
X213193Y172474D01*
X212184Y175235D01*
X193646Y203557D01*
X193600Y203700D01*
X193172Y204998D01*
X192860Y209650D01*
X192859D01*
X192858Y209651D01*
Y209742D01*
G03X191269Y213578I-5425J0D01*
G01X190413Y214434D01*
G02X189078Y218975I3495J3494D01*
G01Y218976D01*
X189287Y220671D01*
X189465Y222189D01*
X188715Y225917D01*
Y229162D01*
G02X189848Y231898I3871J0D01*
G02X189995Y232038I2742J-2732D01*
G01X190147Y232114D01*
X190594Y232337D01*
X190595Y232338D01*
G03X190819Y233008I-223J447D01*
G01X189333Y235984D01*
G01X335442Y-36479D02*
G03X336932Y-34711I-250J1722D01*
G02Y-34704I3118J3D01*
G01Y-34204D01*
X336802Y-33464D01*
Y-33463D01*
X331889Y-26448D01*
X308457Y-10040D01*
X249471Y74201D01*
X232066Y128227D01*
Y129885D01*
X232065Y130500D01*
G03X231153Y132702I-3114J0D01*
G01X230625Y133230D01*
G02X228176Y139144I5916J5914D01*
G01Y147640D01*
G02X230129Y152357I6669J1D01*
G01X230294Y152523D01*
X230457Y152685D01*
G03X232059Y156554I-3871J3869D01*
G01X232060Y156553D01*
Y158019D01*
X228623Y168492D01*
X227138Y172749D01*
X225275Y176677D01*
X223416Y180592D01*
X221416Y183424D01*
X219969Y185472D01*
X219963Y185482D01*
X212329Y201471D01*
X211476Y201773D01*
X210830Y203127D01*
X211131Y203980D01*
X210485Y205334D01*
X209632Y205635D01*
X208985Y206989D01*
X209287Y207842D01*
X208641Y209196D01*
Y211676D01*
G02X209487Y213720I2892J0D01*
G01X211591Y215825D01*
G03X212500Y218019I-2187J2191D01*
G01Y228467D01*
G03X211447Y231173I-4005J-1D01*
G01X211179Y231307D01*
X211178D01*
G03X210507Y231084I-224J-447D01*
G01X209018Y228109D01*
G01X224763D02*
X226257Y231084D01*
G02X226928Y231307I447J-224D01*
G01X226929D01*
X227197Y231173D01*
G02X228249Y228468I-2952J-2705D01*
G02X227884Y222912I-42463J0D01*
G01X227875Y222837D01*
Y218291D01*
G02X227501Y216745I-3080J-73D01*
G01X227124Y216052D01*
G02X227038Y215938I-438J241D01*
G01X225524Y214425D01*
G03X224469Y211875I2553J-2550D01*
G01Y208476D01*
X225251Y207196D01*
X225038Y206316D01*
X225820Y205036D01*
X226700Y204823D01*
X227481Y203543D01*
X227269Y202663D01*
X228051Y201383D01*
X228930Y201171D01*
Y201170D01*
X233455Y193762D01*
X237909Y186448D01*
X247815Y157543D01*
X247804Y156554D01*
G02X246202Y152684I-5473J-1D01*
G01X245874Y152357D01*
G03X243921Y147640I4716J-4716D01*
G01Y139144D01*
G03X246370Y133230I8365J0D01*
G01X246898Y132702D01*
G02X247810Y130500I-2202J-2202D01*
G01Y129270D01*
X247811Y128965D01*
Y128452D01*
X250296Y112256D01*
X267042Y63078D01*
X314339Y-4471D01*
X326713Y-13135D01*
X338754Y-21566D01*
X346856Y-33137D01*
X347132Y-34703D01*
G02X345642Y-36479I-1740J-54D01*
G01X354621Y-46464D02*
G02X353261Y-44653I607J1872D01*
G01Y-41923D01*
X353088Y-39873D01*
X353332Y-37884D01*
Y-33082D01*
X343258Y-18696D01*
X318477Y-1343D01*
X318463D01*
X318103Y-983D01*
X277265Y57339D01*
X264795Y128062D01*
Y128064D01*
X264711Y128540D01*
Y130500D01*
G03X263462Y133516I-4266J0D01*
G01X262934Y134044D01*
G02X260821Y139145I5101J5101D01*
G01Y147640D01*
G02X262437Y151543I5519J1D01*
G01X262765Y151870D01*
G03X264704Y156419I-4684J4684D01*
G03Y156663I-6623J122D01*
G01X264672Y156776D01*
X264671Y156780D01*
X264269Y158332D01*
X264154Y158675D01*
X262156Y163514D01*
X261399Y164692D01*
X241819Y195149D01*
X240243Y197599D01*
X240436Y198484D01*
X239624Y199745D01*
X238740Y199938D01*
X237929Y201199D01*
X238121Y202084D01*
X237310Y203346D01*
X236426Y203538D01*
X235614Y204800D01*
X235807Y205684D01*
X234996Y206946D01*
X234111Y207138D01*
X233300Y208400D01*
X233035Y211124D01*
G02X233965Y213369I3175J0D01*
G01X234412Y213593D01*
X234413D01*
G02X235084Y213370I224J-447D01*
G01X236573Y210394D01*
G01X350621Y-46464D02*
G03X352111Y-44688I-250J1722D01*
G01Y-41972D01*
X351931Y-39851D01*
X352182Y-37813D01*
Y-33445D01*
X342432Y-19522D01*
X317651Y-2169D01*
X317649Y-2167D01*
Y-2157D01*
X317218Y-1726D01*
X276176Y56888D01*
X263561Y128437D01*
Y128965D01*
X263560Y129270D01*
Y130500D01*
G03X262648Y132702I-3114J0D01*
G01X262120Y133230D01*
G02X259671Y139144I5916J5914D01*
G01Y147640D01*
G02X261624Y152357I6669J1D01*
G01X261625Y152358D01*
X261952Y152684D01*
G03X263553Y156442I-3871J3869D01*
G01X263565Y156464D01*
X263560Y156482D01*
X263166Y158004D01*
X263076Y158272D01*
X261132Y162979D01*
X232182Y208012D01*
X231885Y211064D01*
G02X233296Y214321I4325J60D01*
G01X233517Y214432D01*
X233898Y214623D01*
X233899D01*
G03X234122Y215294I-224J447D01*
G01X232638Y218269D01*
G01X244448Y235984D02*
X242964Y233008D01*
G03X243187Y232337I447J-224D01*
G01X243188D01*
X243635Y232113D01*
G02X245145Y228468I-3645J-3645D01*
G01Y218019D01*
G02X243900Y215011I-4247J-4D01*
G01X241796Y212906D01*
G03X241286Y211675I1231J-1231D01*
G01Y209457D01*
X241549Y208569D01*
X241634Y208364D01*
Y208365D01*
X241653Y208319D01*
X241858Y207995D01*
X258898Y189505D01*
Y189503D01*
X258900Y189500D01*
X269374Y169330D01*
X269376Y169321D01*
X272580Y158266D01*
Y156554D01*
G02X270640Y151870I-6624J0D01*
G01X270312Y151543D01*
G03X268696Y147640I3903J-3902D01*
G01Y139145D01*
G03X270809Y134044I7214J0D01*
G01X271337Y133516D01*
G02X272586Y130500I-3017J-3016D01*
G01Y128540D01*
X272826Y127179D01*
Y127178D01*
X286069Y52077D01*
X321135Y1996D01*
X346434Y-15721D01*
X358294Y-32654D01*
X358462Y-33604D01*
X358482Y-34668D01*
G03X359842Y-36479I1967J61D01*
G01X240513Y228109D02*
X242002Y231084D01*
G02X242673Y231307I447J-224D01*
G01X242674D01*
X242942Y231173D01*
G02X243995Y228467I-2952J-2707D01*
G01Y218019D01*
G02X243086Y215825I-3096J-3D01*
G01X240982Y213720D01*
G03X240136Y211676I2046J-2044D01*
G01Y209290D01*
X240463Y208186D01*
X240647Y207738D01*
X240660Y207735D01*
X240942Y207291D01*
X241959Y206188D01*
X241922Y205284D01*
X242938Y204181D01*
X243842Y204144D01*
X244859Y203041D01*
X244822Y202136D01*
X245839Y201033D01*
X246743Y200996D01*
X247759Y199893D01*
X249643Y197849D01*
X257947Y188838D01*
X268300Y168900D01*
X271430Y158102D01*
Y156553D01*
X271429Y156554D01*
G02X269827Y152684I-5473J-1D01*
G01X269499Y152357D01*
G03X267546Y147640I4716J-4716D01*
G01Y139144D01*
G03X269995Y133230I8365J0D01*
G01X270523Y132702D01*
G02X271435Y130500I-2202J-2202D01*
G01Y129270D01*
X271436Y128965D01*
Y128439D01*
X271737Y126728D01*
X284980Y51626D01*
X320309Y1170D01*
X345608Y-16547D01*
X357205Y-33105D01*
X357313Y-33716D01*
X357332Y-34703D01*
G02X355842Y-36479I-1740J-54D01*
G01X364821Y-46464D02*
G02X363552Y-43910I1936J2554D01*
G03X363466Y-40592I-15849J1249D01*
G02Y-38041I9702J1275D01*
G01Y-38040D01*
G03X363376Y-35073I-9147J1207D01*
G01X363051Y-33396D01*
X362901Y-32628D01*
X362792Y-32410D01*
X348432Y-11902D01*
X323152Y5798D01*
X295010Y45999D01*
X280559Y127952D01*
X280456Y128540D01*
Y130500D01*
G03X279207Y133516I-4266J0D01*
G01X278679Y134044D01*
G02X276566Y139145I5101J5101D01*
G01Y147640D01*
G02X278182Y151543I5519J1D01*
G01X278510Y151870D01*
G03X280450Y156554I-4684J4684D01*
G01Y156637D01*
X280461Y157622D01*
X280268Y159055D01*
X272805Y180991D01*
X272800Y181000D01*
X271141Y184600D01*
X264891Y194626D01*
X265096Y195507D01*
X264302Y196780D01*
X263421Y196985D01*
X262627Y198258D01*
X262832Y199139D01*
X262038Y200412D01*
X261157Y200617D01*
X260363Y201890D01*
X260568Y202772D01*
X259774Y204045D01*
X258893Y204249D01*
X258099Y205522D01*
X257285Y206336D01*
G02X256660Y207845I1509J1509D01*
G01Y211124D01*
G02X257590Y213369I3175J0D01*
G01X258037Y213593D01*
X258038D01*
G02X258709Y213370I224J-447D01*
G01X260198Y210394D01*
G01X360821Y-46464D02*
G03X362311Y-44688I-250J1722D01*
G03X362405Y-43820I-14609J2021D01*
G03X362325Y-40741I-14702J1159D01*
G02Y-37890I10843J1426D01*
G03X362247Y-35292I-8006J1060D01*
G01X361921Y-33615D01*
X361802Y-33002D01*
X361801Y-33000D01*
X347606Y-12728D01*
X322326Y4972D01*
X293921Y45548D01*
X279487Y127405D01*
X279306Y128439D01*
Y128965D01*
X279305Y129270D01*
Y130500D01*
G03X278393Y132702I-3114J0D01*
G01X277865Y133230D01*
G02X275416Y139144I5916J5914D01*
G01Y147640D01*
G02X277369Y152357I6669J1D01*
G01X277697Y152684D01*
G03X279299Y156554I-3871J3869D01*
G01X279310Y157551D01*
X279143Y158790D01*
X271713Y180610D01*
X270126Y184052D01*
X269879Y184448D01*
X269671Y184781D01*
X269672D01*
X257192Y204801D01*
X256471Y205522D01*
G02X255510Y207845I2324J2322D01*
G01Y211125D01*
G02X256921Y214321I4325J0D01*
G01X257142Y214432D01*
X257523Y214623D01*
X257524D01*
G03X257747Y215294I-224J447D01*
G01X256258Y218269D01*
G01X370042Y-36479D02*
G02X368682Y-34668I607J1872D01*
G01X368322Y-32633D01*
G03X368132Y-32173I-1133J-199D01*
G01X353190Y-10839D01*
G03X352908Y-10557I-942J-660D01*
G01X325771Y8444D01*
X300656Y44308D01*
X288331Y128540D01*
Y130500D01*
G03X287082Y133516I-4266J0D01*
G01X286554Y134044D01*
G02X284441Y139145I5101J5101D01*
G01Y147640D01*
G02X286057Y151543I5519J1D01*
G01X286385Y151870D01*
G03X288325Y156554I-4684J4684D01*
G01Y157704D01*
X286900Y161300D01*
X264929Y208397D01*
Y211062D01*
G02X265880Y213659I2930J400D01*
G03X267881Y216195I-6407J7112D01*
G03X268395Y218317I-3716J2023D01*
G01Y222761D01*
G03X268770Y228468I-43239J5707D01*
G03X267260Y232113I-5155J0D01*
G01X266813Y232337D01*
X266812D01*
G02X266589Y233008I224J447D01*
G01X268073Y235984D01*
G01X366042Y-36479D02*
G03X367532Y-34775I-250J1722D01*
G01X367189Y-32833D01*
Y-32832D01*
X352248Y-11499D01*
X324945Y7618D01*
X299567Y43857D01*
X299518Y44142D01*
X287181Y128456D01*
Y128965D01*
X287180Y129270D01*
Y130500D01*
G03X286268Y132702I-3114J0D01*
G01X285740Y133230D01*
G02X283291Y139144I5916J5914D01*
G01Y147640D01*
G02X285244Y152357I6669J1D01*
G01X285572Y152684D01*
G03X287174Y156554I-3871J3869D01*
G01Y157487D01*
X287173D01*
X285846Y160836D01*
X267496Y200174D01*
X266645Y200484D01*
X266011Y201843D01*
X266320Y202694D01*
X265686Y204053D01*
X264836Y204362D01*
X264202Y205722D01*
X264511Y206572D01*
X263779Y208142D01*
Y210990D01*
G02X265110Y214514I4080J472D01*
G03X266871Y216745I-5636J6259D01*
G03X267245Y218303I-2706J1473D01*
G01Y222837D01*
X267254Y222912D01*
G03X267619Y228468I-42098J5556D01*
G03X266567Y231173I-4004J0D01*
G01X266299Y231307D01*
X266298D01*
G03X265627Y231084I-224J-447D01*
G01X264133Y228109D01*
G01X375021Y-46464D02*
G02X373661Y-44653I607J1872D01*
G01Y-41950D01*
G03X373675Y-40724I-22854J874D01*
G03X373666Y-40592I-972J0D01*
G02Y-38041I9702J1275D01*
G01Y-38040D01*
G03X373727Y-36238I-9147J1212D01*
G03X373588Y-35132I-9207J-595D01*
G01X372879Y-31349D01*
X357174Y-8918D01*
X328734Y10997D01*
X307253Y41670D01*
X296333Y103599D01*
X296206Y130500D01*
G03X294957Y133516I-4266J0D01*
G01X294429Y134044D01*
G02X292316Y139145I5101J5101D01*
G01Y147640D01*
G02X293932Y151543I5519J1D01*
G01X294260Y151870D01*
G03X296200Y156554I-4684J4684D01*
G01Y157704D01*
X293600Y165600D01*
X279299Y193781D01*
X279581Y194641D01*
X278902Y195979D01*
X278041Y196260D01*
X277363Y197598D01*
X277644Y198458D01*
X276965Y199796D01*
X276105Y200077D01*
X275426Y201414D01*
X275707Y202275D01*
X275028Y203612D01*
X274168Y203893D01*
X273489Y205231D01*
X272604Y207003D01*
Y211091D01*
G02X273517Y213459I3527J0D01*
G01X273776Y213588D01*
X273786Y213593D01*
X273787D01*
G02X274457Y213369I223J-447D01*
G01X275943Y210394D01*
G01X291693D02*
X290207Y213369D01*
G03X289537Y213593I-447J-223D01*
G01X289536D01*
X289267Y213459D01*
G03X288354Y211091I2614J-2368D01*
G01X288473Y208992D01*
X288824Y207534D01*
X289596Y207061D01*
X289947Y205603D01*
X289475Y204831D01*
X289826Y203373D01*
X290598Y202900D01*
X290949Y201442D01*
X290476Y200670D01*
X290827Y199211D01*
X291599Y198739D01*
X291951Y197281D01*
X291478Y196509D01*
X293123Y189675D01*
X311756Y158701D01*
X311902Y157059D01*
X311948Y156560D01*
Y156557D01*
X311950Y156555D01*
Y156554D01*
G02X311949Y156429I-6624J-10D01*
G02X310010Y151870I-6623J125D01*
G01X309682Y151543D01*
G03X308066Y147640I3903J-3902D01*
G01Y139145D01*
G03X310179Y134044I7214J0D01*
G01X310707Y133516D01*
G02X311956Y130500I-3017J-3016D01*
G01X311959Y128849D01*
Y128349D01*
X307941Y105552D01*
X310587Y90544D01*
X315287Y63891D01*
X319928Y37569D01*
X334106Y17320D01*
X365042Y-4342D01*
X382711Y-29579D01*
X383777Y-35073D01*
G02X383866Y-38041I-9057J-1757D01*
G03Y-40592I9702J-1276D01*
G01Y-43826D01*
G03X385221Y-46464I3245J0D01*
G01X272008Y218269D02*
X273495Y215292D01*
G02X273271Y214621I-448J-223D01*
G01X273270D01*
X273263Y214618D01*
X272824Y214399D01*
G03X271454Y211092I3307J-3307D01*
G01Y206731D01*
X272492Y204653D01*
X292534Y165159D01*
X295049Y157522D01*
Y156554D01*
G02X293447Y152684I-5473J-1D01*
G01X293119Y152357D01*
G03X291166Y147640I4716J-4716D01*
G01Y139144D01*
G03X293615Y133230I8365J0D01*
G01X294143Y132702D01*
G02X295055Y130500I-2202J-2202D01*
G01Y130495D01*
X295056D01*
X295119Y117045D01*
X295183Y103496D01*
X306164Y41219D01*
X327908Y10171D01*
X356348Y-9744D01*
X364072Y-20776D01*
X364071D01*
X371794Y-31805D01*
X372457Y-35344D01*
G02X372578Y-36312I-7938J-1484D01*
G02X372525Y-37890I-8059J-519D01*
G03Y-40741I10843J-1426D01*
G02X372511Y-41927I-21718J-337D01*
G01Y-44688D01*
G02X371021Y-46464I-1740J-54D01*
G01X381221D02*
G03X382712Y-43974I-1334J2490D01*
G01Y-43800D01*
G02X382716Y-42329I556392J-777D01*
G01Y-40666D01*
G02X382725Y-37890I10852J1353D01*
G03X382648Y-35292I-8006J1063D01*
G01X381628Y-30039D01*
X364216Y-5168D01*
X333280Y16494D01*
X318839Y37118D01*
X309512Y90015D01*
Y90016D01*
X306773Y105552D01*
X310809Y128450D01*
Y128849D01*
X310805Y130500D01*
G03X309893Y132702I-3114J0D01*
G01X309365Y133230D01*
G02X306916Y139144I5916J5914D01*
G01Y147640D01*
G02X308869Y152357I6669J1D01*
G01X309197Y152684D01*
G03X310799Y156451I-3871J3870D01*
G01X310802Y156454D01*
Y156457D01*
X310756Y156956D01*
Y156955D01*
X310634Y158335D01*
X292367Y188700D01*
X292137Y189083D01*
X292005Y189405D01*
X287330Y208823D01*
X287204Y211056D01*
G02X288574Y214399I4677J36D01*
G01X289013Y214618D01*
X289020Y214621D01*
X289021D01*
G03X289245Y215292I-224J448D01*
G01X287758Y218269D01*
G01X380242Y-36479D02*
G02X378882Y-34668I607J1872D01*
G01Y-32921D01*
X377923Y-30152D01*
X377830Y-30020D01*
X361831Y-7173D01*
X331117Y14335D01*
X316133Y35722D01*
X316115Y35730D01*
X316109Y35743D01*
X315917Y36206D01*
X303794Y104376D01*
X302944Y109200D01*
X304081Y129349D01*
Y130500D01*
G03X302832Y133516I-4266J0D01*
G01X302304Y134044D01*
G02X300191Y139145I5101J5101D01*
G01Y147640D01*
G02X301807Y151543I5519J1D01*
G01X302135Y151870D01*
G03X304074Y156437I-4684J4684D01*
G01Y157834D01*
X303755Y159232D01*
X285100Y195400D01*
X281000Y208100D01*
X280738Y209551D01*
Y211873D01*
X280739Y211874D01*
G02X281458Y213611I2458J0D01*
G01X282971Y215124D01*
G03X283254Y215502I-1166J1168D01*
G01X283631Y216195D01*
G03X284145Y218318I-3716J2023D01*
G01Y222761D01*
G03X284520Y228468I-43239J5707D01*
G03X283010Y232113I-5155J0D01*
G01X282563Y232337D01*
X282562D01*
G02X282339Y233008I224J447D01*
G01X283818Y235984D01*
G01X390442Y-36479D02*
G02X389085Y-34718I607J1871D01*
G01X389162Y-33679D01*
X386711Y-28315D01*
X386700Y-28300D01*
X365600Y1700D01*
X358488Y9055D01*
X340039Y21974D01*
X323757Y45228D01*
X314487Y97801D01*
X319850Y128213D01*
Y129864D01*
G02X321240Y133220I4746J0D01*
G01X321666Y133646D01*
G03X323660Y138460I-4814J4814D01*
G01Y148620D01*
G03X322444Y151556I-4152J0D01*
G01X321570Y152430D01*
G02X319801Y156702I4274J4272D01*
G01Y156834D01*
X318795Y161170D01*
X308244Y184588D01*
X296503Y208152D01*
X296483Y208192D01*
Y211875D01*
X296484Y211874D01*
G02X297203Y213611I2458J0D01*
G01X298716Y215124D01*
G03X298999Y215502I-1166J1168D01*
G01X299376Y216195D01*
G03X299890Y218318I-3716J2023D01*
G01Y222761D01*
G03X300265Y228468I-43239J5707D01*
G03X298755Y232113I-5155J0D01*
G01X298308Y232337D01*
X298307D01*
G02X298084Y233008I224J447D01*
G01X299568Y235984D01*
G01X279883Y228109D02*
X281377Y231084D01*
G02X282048Y231307I447J-224D01*
G01X282049D01*
X282317Y231173D01*
G02X283369Y228468I-2952J-2705D01*
G02X283004Y222912I-42463J0D01*
G01X282995Y222837D01*
Y218291D01*
G02X282621Y216745I-3080J-73D01*
G01X282244Y216052D01*
G02X282158Y215938I-438J241D01*
G01X281401Y215182D01*
X280644Y214425D01*
G03X279588Y211874I2553J-2551D01*
G01Y209448D01*
X279868Y207896D01*
X279881Y207820D01*
X280342Y206393D01*
X279929Y205587D01*
X280390Y204159D01*
X281196Y203747D01*
X281657Y202320D01*
X281244Y201514D01*
X281705Y200086D01*
X282511Y199674D01*
X284034Y194956D01*
X302657Y158851D01*
X302924Y157700D01*
Y156448D01*
G02X301322Y152684I-5473J106D01*
G01X300994Y152357D01*
G03X299041Y147640I4716J-4716D01*
G01Y139144D01*
G03X301490Y133230I8365J0D01*
G01X302018Y132702D01*
G02X302930Y130500I-2202J-2202D01*
G01X302931Y129413D01*
X301788Y109132D01*
X302661Y104177D01*
Y104175D01*
X314806Y35881D01*
X315046Y35303D01*
X315052Y35290D01*
X315044Y35271D01*
X330291Y13509D01*
X361005Y-7999D01*
X376888Y-30681D01*
X377732Y-33115D01*
Y-34703D01*
G02X376242Y-36479I-1740J-54D01*
G01X386442D02*
G03X387932Y-34703I-250J1722D01*
G01X387993Y-33888D01*
X385709Y-28890D01*
X364710Y964D01*
X357738Y8176D01*
X339213Y21148D01*
X330956Y32941D01*
X322668Y44777D01*
X313673Y95790D01*
X313319Y97801D01*
X318700Y128314D01*
Y129863D01*
G02X320426Y134034I5897J3D01*
G01X320852Y134460D01*
G03X322510Y138459I-3999J4001D01*
G01Y148620D01*
G03X321630Y150742I-3002J-1D01*
G01X320756Y151616D01*
G02X318650Y156702I5088J5086D01*
G01X317700Y160800D01*
X307234Y184028D01*
X299290Y199978D01*
X298431Y200265D01*
X297763Y201608D01*
X298050Y202466D01*
X297381Y203809D01*
X296523Y204096D01*
X295854Y205439D01*
X296142Y206297D01*
X295473Y207640D01*
X295333Y207922D01*
Y211874D01*
G02X296389Y214425I3609J0D01*
G01X297903Y215938D01*
G03X297989Y216052I-352J355D01*
G01X298366Y216745D01*
G03X298740Y218291I-2706J1473D01*
G01Y222837D01*
X298749Y222912D01*
G03X299114Y228468I-42098J5556D01*
G03X298062Y231173I-4004J0D01*
G01X297794Y231307D01*
X297793D01*
G03X297122Y231084I-224J-447D01*
G01X295628Y228109D01*
G01X343524Y36971D02*
Y37124D01*
X343800Y37400D01*
Y58298D01*
X349701Y64199D01*
G01X346000Y34640D02*
X345912Y34728D01*
Y56712D01*
X353100Y63900D01*
G01X395421Y-46464D02*
X394567Y-45327D01*
G02X394066Y-43876I1998J1502D01*
G02Y-43826I2499J25D01*
G01Y-40592D01*
G02Y-38041I9702J1275D01*
G03X394000Y-35182I-9146J1219D01*
G01X393999D01*
X393692Y-33544D01*
X393633Y-33337D01*
X391021Y-26652D01*
X368178Y5851D01*
X364842Y9077D01*
X342383Y25023D01*
X327503Y46274D01*
X321644Y79498D01*
X320390Y86610D01*
X327725Y128213D01*
Y129864D01*
G02X329115Y133220I4746J0D01*
G01X329541Y133646D01*
G03X331535Y138460I-4814J4814D01*
G01Y148620D01*
G03X330319Y151556I-4152J0D01*
G01X329445Y152430D01*
G02X327676Y156702I4274J4272D01*
G01Y156812D01*
X327193Y159307D01*
X310297Y188674D01*
X307866Y196330D01*
X308282Y197133D01*
X307828Y198563D01*
X307024Y198979D01*
X306570Y200409D01*
X306986Y201212D01*
X306532Y202642D01*
X305729Y203058D01*
X305275Y204488D01*
X305691Y205292D01*
X305237Y206721D01*
X304433Y207138D01*
X303905Y208800D01*
Y211124D01*
G02X304835Y213369I3175J0D01*
G01X305282Y213593D01*
X305283D01*
G02X305954Y213370I224J-447D01*
G01X307443Y210394D01*
G01X391421Y-46464D02*
G03X392912Y-43900I-1459J2564D01*
G02X392916Y-42329I556392J-631D01*
G01Y-40666D01*
G02X392925Y-37890I10852J1353D01*
G03X392849Y-35292I-8005J1066D01*
G01Y-35289D01*
X392562Y-33756D01*
X390001Y-27203D01*
X390000Y-27200D01*
X389999D01*
X378649Y-11050D01*
X367300Y5100D01*
X364105Y8189D01*
X341555Y24200D01*
X326414Y45823D01*
X323440Y62687D01*
X320476Y79498D01*
X319222Y86610D01*
X326575Y128314D01*
Y129863D01*
G02X328301Y134034I5897J3D01*
G01X328727Y134460D01*
G03X330385Y138459I-3999J4001D01*
G01Y148620D01*
G03X329505Y150742I-3002J-1D01*
G01X328631Y151616D01*
G02X326525Y156702I5088J5086D01*
G01X326100Y158900D01*
X309238Y188208D01*
X302755Y208621D01*
Y211125D01*
G02X304166Y214321I4325J0D01*
G01X304768Y214623D01*
X304769D01*
G03X304992Y215294I-224J447D01*
G01X303503Y218269D01*
G01X315313Y235984D02*
X313826Y233007D01*
G03X314050Y232336I448J-223D01*
G01X314051D01*
X314497Y232114D01*
G02X316144Y228138I-3976J-3976D01*
G01Y217770D01*
G03X317500Y215000I3507J0D01*
G01X317832Y214668D01*
G02X319600Y210400I-4268J-4268D01*
G01Y208100D01*
X318400Y187300D01*
X318700Y183400D01*
X319900Y180300D01*
X327025Y168150D01*
X332700Y161400D01*
X332712Y161386D01*
X335449Y157922D01*
X335565Y156275D01*
G03X337320Y152430I6028J428D01*
G01X338194Y151556D01*
G02X339410Y148620I-2936J-2936D01*
G01Y138460D01*
G02X337416Y133646I-6808J0D01*
G01X336990Y133220D01*
G03X335601Y129873I3357J-3355D01*
G01X335619Y128823D01*
X329454Y93857D01*
X328004Y85632D01*
X335647Y42291D01*
X346358Y27003D01*
X368399Y11572D01*
X370734Y9134D01*
X395300Y-25200D01*
X399282Y-33518D01*
Y-34668D01*
G03X400642Y-36479I1967J61D01*
G01X396642D02*
G03X398132Y-34703I-250J1722D01*
G01X398101Y-33716D01*
X397671Y-32817D01*
X394305Y-25788D01*
X369846Y8397D01*
X367646Y10694D01*
X345532Y26177D01*
X340060Y33987D01*
X337062Y38266D01*
X334558Y41840D01*
X326836Y85632D01*
X328462Y94858D01*
Y94860D01*
X334467Y128913D01*
X334450Y129863D01*
G02X336176Y134034I5897J3D01*
G01X336602Y134460D01*
G03X338260Y138459I-3999J4001D01*
G01Y148620D01*
G03X337380Y150742I-3002J-1D01*
G01X336506Y151616D01*
G02X334417Y156194I5087J5087D01*
G01X334326Y157487D01*
X331820Y160659D01*
X326145Y167409D01*
X326032Y167568D01*
X318861Y179798D01*
X317566Y183143D01*
X317247Y187289D01*
X317957Y199588D01*
X317355Y200264D01*
X317441Y201762D01*
X318117Y202364D01*
X318203Y203861D01*
X317601Y204537D01*
X317688Y206034D01*
X318364Y206636D01*
X318450Y208134D01*
Y210399D01*
G03X317018Y213854I-4885J-1D01*
G01X316733Y214139D01*
G02X314994Y217769I2919J3630D01*
G01Y228137D01*
G03X313806Y231172I-4472J-1D01*
G01X313535Y231308D01*
X313534D01*
G03X312864Y231084I-223J-447D01*
G01X311378Y228109D01*
G01X346150Y84800D02*
X358900Y97550D01*
Y132800D01*
X362200Y136100D01*
Y150500D01*
X358300Y154400D01*
Y159800D01*
X348200Y169900D01*
G01X352138Y50729D02*
Y50838D01*
X359700Y58400D01*
Y91300D01*
X366300Y97900D01*
Y132700D01*
X370300Y136700D01*
Y150800D01*
X366700Y154400D01*
Y157500D01*
X332000Y192200D01*
G01X329400Y195900D02*
X329700Y195600D01*
X331871D01*
X336271Y191200D01*
X341300D01*
X374300Y158200D01*
Y153700D01*
X378100Y149900D01*
Y135600D01*
X374800Y132300D01*
Y101200D01*
X366700Y93100D01*
Y63499D01*
X355536Y52335D01*
Y50589D01*
G01X355399Y47191D02*
Y47835D01*
X382200Y74636D01*
Y132800D01*
X386300Y136900D01*
Y150400D01*
X382700Y154000D01*
Y158200D01*
X345606Y195294D01*
X334794D01*
G01X359023Y47177D02*
X355850Y44004D01*
Y37891D01*
X355370Y37411D01*
G01X455700Y205800D02*
Y202200D01*
X463700Y194200D01*
Y133700D01*
X449900Y119900D01*
X426407D01*
X384700Y78193D01*
Y73400D01*
X359023Y47723D01*
Y47177D01*
G01X349000Y28300D02*
X348250Y29050D01*
Y54350D01*
X349700Y55800D01*
Y56000D01*
G01X355300Y81400D02*
X355896Y80804D01*
Y62896D01*
X349700Y56700D01*
Y56000D01*
G01X356700Y86600D02*
X356900D01*
X358300Y85200D01*
Y61900D01*
X353098Y56698D01*
Y55882D01*
G01X350300Y31800D02*
X349550Y32550D01*
Y52334D01*
X353098Y55882D01*
G01X351500Y36100D02*
X350850Y36750D01*
Y49441D01*
X352138Y50729D01*
G01X352700Y40000D02*
Y47753D01*
X355536Y50589D01*
G01X355399Y47191D02*
X354550Y46342D01*
Y39233D01*
X353520Y38203D01*
Y35680D01*
X355300Y33900D01*
G01X391200Y35700D02*
Y37171D01*
X398106Y44077D01*
Y63720D01*
X398805Y64419D01*
Y66200D01*
G01X388006Y37706D02*
X388906D01*
X396106Y44906D01*
Y63720D01*
X395406Y64420D01*
Y66092D01*
G01X461513Y48758D02*
X462568Y49813D01*
X464607D01*
X466000Y48420D01*
Y46920D01*
X465110Y46030D01*
Y44530D01*
X466000Y43640D01*
Y42140D01*
X465110Y41250D01*
Y39750D01*
X466000Y38860D01*
Y37360D01*
X465110Y36470D01*
Y34970D01*
X466000Y34080D01*
Y32580D01*
X441600Y8180D01*
Y-19580D01*
X447120Y-25100D01*
X523500D01*
X527315Y-28915D01*
Y-37285D01*
X526600Y-38000D01*
X524994D01*
G01X461513Y52267D02*
X462567Y51213D01*
X465187D01*
X467400Y49000D01*
Y32000D01*
X443000Y7600D01*
Y-19000D01*
X447700Y-23700D01*
X524080D01*
X528715Y-28335D01*
Y-37115D01*
X529600Y-38000D01*
X530994D01*
G01X445238Y218269D02*
X448031D01*
X455700Y210600D01*
Y205800D01*
G54D16*
G01X-65001Y-234972D02*
Y-217472D01*
X-60635D01*
X-58888Y-218347D01*
X-57578Y-219514D01*
X-56486Y-221263D01*
X-55613Y-223306D01*
X-55395Y-226222D01*
X-55613Y-229139D01*
X-56486Y-231181D01*
X-57578Y-232931D01*
X-58888Y-234097D01*
X-60635Y-234972D01*
X-65001D01*
G01X-48157Y-217472D02*
X-42698Y-234972D01*
X-37239Y-217472D01*
G01X-25198D02*
Y-234972D01*
G01X-30220Y-217472D02*
X-20176D01*
G01X5435Y-234972D02*
Y-217472D01*
X10894D01*
X12640Y-218347D01*
X13732Y-219514D01*
X14169Y-221847D01*
X13732Y-224181D01*
X12422Y-225639D01*
X10894Y-226514D01*
X5435D01*
G01X10894D02*
X14169Y-234972D01*
G01X27302Y-223306D02*
Y-234972D01*
G01Y-218639D02*
X26865Y-218347D01*
Y-217764D01*
X27302Y-217472D01*
X27739Y-217764D01*
Y-218347D01*
X27302Y-218639D01*
G01X41527Y-232931D02*
X42619Y-234097D01*
X44147Y-234972D01*
X45457D01*
X46767Y-234389D01*
X47640Y-233514D01*
X48077Y-232348D01*
X47859Y-230597D01*
X46985Y-229722D01*
X43055Y-227972D01*
X42182Y-225930D01*
X42619Y-224472D01*
X43492Y-223597D01*
X44802Y-223306D01*
X46112Y-223597D01*
X47422Y-224472D01*
G01X59027Y-227097D02*
X66014D01*
X65359Y-225055D01*
X64267Y-223889D01*
X62739Y-223306D01*
X61210Y-223597D01*
X59900Y-224472D01*
X59027Y-226514D01*
X58590Y-228264D01*
Y-230014D01*
X59027Y-231764D01*
X60119Y-233514D01*
X61429Y-234680D01*
X62957Y-234972D01*
X64485Y-234389D01*
X66014Y-232639D01*
G01X76745Y-234972D02*
Y-223306D01*
G01Y-225639D02*
X77837Y-224472D01*
X78929Y-223597D01*
X80457Y-223306D01*
X81548Y-223597D01*
X82859Y-224472D01*
G01X119605Y-218931D02*
X118295Y-218055D01*
X116767Y-217472D01*
X115020D01*
X113055Y-218347D01*
X111527Y-219805D01*
X110435Y-221556D01*
X109562Y-224472D01*
X109343Y-227097D01*
X109780Y-229722D01*
X110435Y-231472D01*
X111745Y-233222D01*
X113274Y-234389D01*
X114802Y-234972D01*
X116330D01*
X117859Y-234389D01*
X119169Y-233514D01*
X120261Y-232348D01*
G01X136232Y-234972D02*
Y-223306D01*
G01Y-225347D02*
X135359Y-224181D01*
X134048Y-223597D01*
X132520Y-223306D01*
X130992Y-223889D01*
X129682Y-225055D01*
X128808Y-226805D01*
X128372Y-229139D01*
X128808Y-231472D01*
X129682Y-233222D01*
X130992Y-234389D01*
X132520Y-234972D01*
X134048Y-234680D01*
X135359Y-233806D01*
X136232Y-232639D01*
G01X146745Y-234972D02*
Y-223306D01*
G01Y-225639D02*
X147837Y-224472D01*
X148929Y-223597D01*
X150457Y-223306D01*
X151548Y-223597D01*
X152859Y-224472D01*
G01X171232Y-217472D02*
Y-234972D01*
G01Y-232348D02*
X170359Y-233806D01*
X169048Y-234680D01*
X167520Y-234972D01*
X165774Y-234389D01*
X164464Y-232931D01*
X163590Y-231181D01*
X163372Y-229139D01*
X163590Y-227097D01*
X164464Y-225347D01*
X165774Y-223889D01*
X167520Y-223306D01*
X169048Y-223597D01*
X170140Y-224181D01*
X171232Y-225347D01*
G01X178252Y-240805D02*
X191352D01*
G01X197717Y-232639D02*
X199464Y-234097D01*
X201429Y-234972D01*
X203175D01*
X204922Y-234097D01*
X206232Y-232639D01*
X206887Y-230597D01*
X206450Y-228556D01*
X205359Y-226805D01*
X203394Y-225639D01*
X200774Y-225055D01*
X199245Y-223889D01*
X198590Y-221847D01*
X199027Y-219805D01*
X200119Y-218347D01*
X201647Y-217472D01*
X203175D01*
X204704Y-218055D01*
X206014Y-219514D01*
G01X215217Y-232639D02*
X216964Y-234097D01*
X218929Y-234972D01*
X220675D01*
X222422Y-234097D01*
X223732Y-232639D01*
X224387Y-230597D01*
X223950Y-228556D01*
X222859Y-226805D01*
X220894Y-225639D01*
X218274Y-225055D01*
X216745Y-223889D01*
X216090Y-221847D01*
X216527Y-219805D01*
X217619Y-218347D01*
X219147Y-217472D01*
X220675D01*
X222204Y-218055D01*
X223514Y-219514D01*
G01X250654Y-220389D02*
X251964Y-218639D01*
X253492Y-217764D01*
X255239Y-217472D01*
X257422Y-218055D01*
X258950Y-219514D01*
X259387Y-221263D01*
X259169Y-223014D01*
X258295Y-224472D01*
X253929Y-227389D01*
X251964Y-229430D01*
X250654Y-232348D01*
X250217Y-234972D01*
X259387D01*
G01X286527Y-232931D02*
X287619Y-234097D01*
X289147Y-234972D01*
X290457D01*
X291767Y-234389D01*
X292640Y-233514D01*
X293077Y-232348D01*
X292859Y-230597D01*
X291985Y-229722D01*
X288055Y-227972D01*
X287182Y-225930D01*
X287619Y-224472D01*
X288492Y-223597D01*
X289802Y-223306D01*
X291112Y-223597D01*
X292422Y-224472D01*
G01X307302Y-234972D02*
Y-217472D01*
G01X324802Y-234972D02*
X323492Y-234680D01*
X322182Y-233514D01*
X321308Y-231472D01*
X320872Y-229139D01*
X321308Y-226805D01*
X322182Y-224764D01*
X323492Y-223597D01*
X324802Y-223306D01*
X326112Y-223597D01*
X327422Y-224764D01*
X328295Y-226805D01*
X328514Y-229139D01*
X328295Y-231472D01*
X327422Y-233514D01*
X326112Y-234680D01*
X324802Y-234972D01*
G01X342302Y-217472D02*
Y-234972D01*
G01X339245Y-223306D02*
X345359D01*
G01X356527Y-232931D02*
X357619Y-234097D01*
X359147Y-234972D01*
X360457D01*
X361767Y-234389D01*
X362640Y-233514D01*
X363077Y-232348D01*
X362859Y-230597D01*
X361985Y-229722D01*
X358055Y-227972D01*
X357182Y-225930D01*
X357619Y-224472D01*
X358492Y-223597D01*
X359802Y-223306D01*
X361112Y-223597D01*
X362422Y-224472D01*
G01X109125Y-189972D02*
Y-172472D01*
X114802Y-187055D01*
X120479Y-172472D01*
Y-189972D01*
G01X132302D02*
X130992Y-189680D01*
X129682Y-188514D01*
X128808Y-186472D01*
X128372Y-184139D01*
X128808Y-181805D01*
X129682Y-179764D01*
X130992Y-178597D01*
X132302Y-178306D01*
X133612Y-178597D01*
X134922Y-179764D01*
X135795Y-181805D01*
X136014Y-184139D01*
X135795Y-186472D01*
X134922Y-188514D01*
X133612Y-189680D01*
X132302Y-189972D01*
G01X153732Y-172472D02*
Y-189972D01*
G01Y-187348D02*
X152859Y-188806D01*
X151548Y-189680D01*
X150020Y-189972D01*
X148274Y-189389D01*
X146964Y-187931D01*
X146090Y-186181D01*
X145872Y-184139D01*
X146090Y-182097D01*
X146964Y-180347D01*
X148274Y-178889D01*
X150020Y-178306D01*
X151548Y-178597D01*
X152640Y-179181D01*
X153732Y-180347D01*
G01X164027Y-182097D02*
X171014D01*
X170359Y-180055D01*
X169267Y-178889D01*
X167739Y-178306D01*
X166210Y-178597D01*
X164900Y-179472D01*
X164027Y-181514D01*
X163590Y-183264D01*
Y-185014D01*
X164027Y-186764D01*
X165119Y-188514D01*
X166429Y-189680D01*
X167957Y-189972D01*
X169485Y-189389D01*
X171014Y-187639D01*
G01X184802Y-189972D02*
Y-172472D01*
G01X418602Y-234972D02*
Y-217472D01*
X415982Y-220972D01*
G01Y-234972D02*
X421222D01*
G01X431299Y-232348D02*
X432608Y-233806D01*
X434137Y-234680D01*
X436102Y-234972D01*
X438067Y-234389D01*
X439595Y-233222D01*
X440687Y-231181D01*
X440905Y-228847D01*
X440469Y-226514D01*
X439377Y-225055D01*
X437848Y-223889D01*
X436320Y-223597D01*
X434792Y-223889D01*
X432827Y-225055D01*
X433482Y-217472D01*
X439377D01*
G01X449890Y-232931D02*
X451419Y-234389D01*
X453165Y-234972D01*
X454912Y-234389D01*
X456440Y-232639D01*
X457532Y-230014D01*
X457969Y-227389D01*
Y-224181D01*
X457532Y-221556D01*
X456440Y-219222D01*
X455130Y-218055D01*
X453602Y-217472D01*
X451855Y-218055D01*
X450545Y-219222D01*
X449672Y-220972D01*
X449235Y-223306D01*
X449672Y-225347D01*
X450764Y-227389D01*
X452074Y-228556D01*
X453602Y-228847D01*
X455348Y-228264D01*
X456659Y-226805D01*
X457969Y-224181D01*
G01X466954Y-227681D02*
X468482Y-225639D01*
X469792Y-224472D01*
X471539Y-223889D01*
X473067Y-224472D01*
X474159Y-225639D01*
X475032Y-227389D01*
X475250Y-229430D01*
X475032Y-231181D01*
X474159Y-232931D01*
X472848Y-234389D01*
X471320Y-234972D01*
X469574Y-234389D01*
X468045Y-232639D01*
X467172Y-230014D01*
X466954Y-227097D01*
X467390Y-223306D01*
X468045Y-221263D01*
X469137Y-219222D01*
X470665Y-217764D01*
X472194Y-217472D01*
X473722Y-218055D01*
X474814Y-219514D01*
G01X488602Y-234972D02*
X490130Y-234680D01*
X491877Y-233806D01*
X492969Y-232348D01*
X493405Y-230305D01*
X492969Y-228264D01*
X491659Y-226514D01*
X489694Y-225639D01*
X487510D01*
X486200Y-225055D01*
X485108Y-223597D01*
X484672Y-221556D01*
X485327Y-219514D01*
X486855Y-218055D01*
X488602Y-217472D01*
X490348Y-218055D01*
X491877Y-219514D01*
X492532Y-221556D01*
X492095Y-223597D01*
X491004Y-225055D01*
X489694Y-225639D01*
X487510D01*
X485545Y-226514D01*
X484235Y-228264D01*
X483799Y-230305D01*
X484235Y-232348D01*
X485327Y-233806D01*
X487074Y-234680D01*
X488602Y-234972D01*
G01X405485Y-189972D02*
Y-172472D01*
X410725D01*
X412472Y-173347D01*
X413782Y-175389D01*
X414219Y-177722D01*
X413782Y-180055D01*
X412690Y-181805D01*
X410725Y-182681D01*
X405485D01*
G01X432155Y-173931D02*
X430845Y-173055D01*
X429317Y-172472D01*
X427570D01*
X425605Y-173347D01*
X424077Y-174805D01*
X422985Y-176556D01*
X422112Y-179472D01*
X421893Y-182097D01*
X422330Y-184722D01*
X422985Y-186472D01*
X424295Y-188222D01*
X425824Y-189389D01*
X427352Y-189972D01*
X428880D01*
X430409Y-189389D01*
X431719Y-188514D01*
X432811Y-187348D01*
G01X446598Y-180639D02*
X447472Y-179764D01*
X448127Y-178306D01*
X448564Y-176263D01*
X448127Y-174514D01*
X447254Y-173347D01*
X445725Y-172472D01*
X439830D01*
Y-189972D01*
X447035D01*
X448564Y-188806D01*
X449437Y-187055D01*
X449874Y-185014D01*
X449437Y-182972D01*
X448127Y-181222D01*
X446598Y-180639D01*
X439830D01*
G01X455802Y-195805D02*
X468902D01*
G01X474830Y-189972D02*
Y-172472D01*
X484874Y-189972D01*
Y-172472D01*
G01X497352Y-189972D02*
X495605Y-189680D01*
X494077Y-188514D01*
X492767Y-186764D01*
X491893Y-184722D01*
X491457Y-182389D01*
Y-180055D01*
X491893Y-177722D01*
X492767Y-175680D01*
X494077Y-173931D01*
X495605Y-172764D01*
X497352Y-172472D01*
X499098Y-172764D01*
X500627Y-173931D01*
X501937Y-175680D01*
X502811Y-177722D01*
X503247Y-180055D01*
Y-182389D01*
X502811Y-184722D01*
X501937Y-186764D01*
X500627Y-188514D01*
X499098Y-189680D01*
X497352Y-189972D01*
G01X571152Y-234972D02*
Y-217472D01*
X568532Y-220972D01*
G01Y-234972D02*
X573772D01*
G01X583193D02*
X588652Y-217472D01*
X594111Y-234972D01*
G01X592145Y-228847D02*
X585158D01*
G01X548193Y-172472D02*
X553652Y-189972D01*
X559111Y-172472D01*
G01X575519Y-189972D02*
X566785D01*
Y-172472D01*
X575519D01*
G01X572025Y-180930D02*
X566785D01*
G01X584285Y-189972D02*
Y-172472D01*
X589744D01*
X591490Y-173347D01*
X592582Y-174514D01*
X593019Y-176847D01*
X592582Y-179181D01*
X591272Y-180639D01*
X589744Y-181514D01*
X584285D01*
G01X589744D02*
X593019Y-189972D01*
G01X606152Y-190555D02*
X605715Y-190264D01*
Y-189680D01*
X606152Y-189389D01*
X606589Y-189680D01*
Y-190264D01*
X606152Y-190555D01*
G01X707985Y-217472D02*
Y-234972D01*
X716719D01*
G01X725049Y-231472D02*
X726358Y-233514D01*
X728105Y-234680D01*
X730070Y-234972D01*
X731817Y-234680D01*
X733564Y-233222D01*
X734655Y-231472D01*
X734874Y-229722D01*
X734437Y-227681D01*
X732909Y-226222D01*
X731380Y-225639D01*
X729415D01*
G01X731380D02*
X732690Y-224764D01*
X733782Y-223306D01*
X734219Y-221556D01*
X733782Y-219805D01*
X732690Y-218347D01*
X730725Y-217472D01*
X728760Y-217764D01*
X726795Y-218931D01*
G01X681735Y-172472D02*
Y-189972D01*
X690469D01*
G01X707532D02*
Y-178306D01*
G01Y-180347D02*
X706659Y-179181D01*
X705348Y-178597D01*
X703820Y-178306D01*
X702292Y-178889D01*
X700982Y-180055D01*
X700108Y-181805D01*
X699672Y-184139D01*
X700108Y-186472D01*
X700982Y-188222D01*
X702292Y-189389D01*
X703820Y-189972D01*
X705348Y-189680D01*
X706659Y-188806D01*
X707532Y-187639D01*
G01X716517Y-195222D02*
X717827Y-195805D01*
X719574Y-195222D01*
X720665Y-194056D01*
X721539Y-192597D01*
X722848Y-187931D01*
X725687Y-178306D01*
G01X718700D02*
X722848Y-187931D01*
G01X735327Y-182097D02*
X742314D01*
X741659Y-180055D01*
X740567Y-178889D01*
X739039Y-178306D01*
X737510Y-178597D01*
X736200Y-179472D01*
X735327Y-181514D01*
X734890Y-183264D01*
Y-185014D01*
X735327Y-186764D01*
X736419Y-188514D01*
X737729Y-189680D01*
X739257Y-189972D01*
X740785Y-189389D01*
X742314Y-187639D01*
G01X753045Y-189972D02*
Y-178306D01*
G01Y-180639D02*
X754137Y-179472D01*
X755229Y-178597D01*
X756757Y-178306D01*
X757848Y-178597D01*
X759159Y-179472D01*
G01X824705Y-218931D02*
X823395Y-218055D01*
X821867Y-217472D01*
X820120D01*
X818155Y-218347D01*
X816627Y-219805D01*
X815535Y-221556D01*
X814662Y-224472D01*
X814443Y-227097D01*
X814880Y-229722D01*
X815535Y-231472D01*
X816845Y-233222D01*
X818374Y-234389D01*
X819902Y-234972D01*
X821430D01*
X822959Y-234389D01*
X824269Y-233514D01*
X825361Y-232348D01*
G01X837402Y-234972D02*
X835655Y-234680D01*
X834127Y-233514D01*
X832817Y-231764D01*
X831943Y-229722D01*
X831507Y-227389D01*
Y-225055D01*
X831943Y-222722D01*
X832817Y-220680D01*
X834127Y-218931D01*
X835655Y-217764D01*
X837402Y-217472D01*
X839148Y-217764D01*
X840677Y-218931D01*
X841987Y-220680D01*
X842861Y-222722D01*
X843297Y-225055D01*
Y-227389D01*
X842861Y-229722D01*
X841987Y-231764D01*
X840677Y-233514D01*
X839148Y-234680D01*
X837402Y-234972D01*
G01X849880D02*
Y-217472D01*
X859924Y-234972D01*
Y-217472D01*
G01X867380Y-234972D02*
Y-217472D01*
X877424Y-234972D01*
Y-217472D01*
G01X887282D02*
X892522D01*
G01X889902D02*
Y-234972D01*
G01X887282D02*
X892522D01*
G01X911769D02*
X903035D01*
Y-217472D01*
X911769D01*
G01X908275Y-225930D02*
X903035D01*
G01X937817Y-234972D02*
X946987Y-217472D01*
G01X937817D02*
X946987Y-234972D01*
G01X955317D02*
Y-217472D01*
G01X964487D02*
Y-234972D01*
G01Y-226222D02*
X955317D01*
G01X823849Y-189972D02*
Y-172472D01*
X828215D01*
X829962Y-173347D01*
X831272Y-174514D01*
X832364Y-176263D01*
X833237Y-178306D01*
X833455Y-181222D01*
X833237Y-184139D01*
X832364Y-186181D01*
X831272Y-187931D01*
X829962Y-189097D01*
X828215Y-189972D01*
X823849D01*
G01X842877Y-182097D02*
X849864D01*
X849209Y-180055D01*
X848117Y-178889D01*
X846589Y-178306D01*
X845060Y-178597D01*
X843750Y-179472D01*
X842877Y-181514D01*
X842440Y-183264D01*
Y-185014D01*
X842877Y-186764D01*
X843969Y-188514D01*
X845279Y-189680D01*
X846807Y-189972D01*
X848335Y-189389D01*
X849864Y-187639D01*
G01X860377Y-187931D02*
X861469Y-189097D01*
X862997Y-189972D01*
X864307D01*
X865617Y-189389D01*
X866490Y-188514D01*
X866927Y-187348D01*
X866709Y-185597D01*
X865835Y-184722D01*
X861905Y-182972D01*
X861032Y-180930D01*
X861469Y-179472D01*
X862342Y-178597D01*
X863652Y-178306D01*
X864962Y-178597D01*
X866272Y-179472D01*
G01X881152Y-178306D02*
Y-189972D01*
G01Y-173639D02*
X880715Y-173347D01*
Y-172764D01*
X881152Y-172472D01*
X881589Y-172764D01*
Y-173347D01*
X881152Y-173639D01*
G01X895595Y-194347D02*
X897124Y-195514D01*
X898870Y-195805D01*
X900398Y-195514D01*
X901709Y-194056D01*
X902582Y-192014D01*
Y-178306D01*
G01Y-180639D02*
X901709Y-179472D01*
X900398Y-178597D01*
X898870Y-178306D01*
X897124Y-178889D01*
X896032Y-180055D01*
X895158Y-182097D01*
X894722Y-184139D01*
X894940Y-185889D01*
X895814Y-187931D01*
X897124Y-189389D01*
X898870Y-189972D01*
X900180Y-189680D01*
X901709Y-188514D01*
X902582Y-187348D01*
G01X912440Y-189972D02*
Y-178306D01*
G01Y-181222D02*
X913314Y-179764D01*
X914624Y-178597D01*
X916370Y-178306D01*
X917898Y-178597D01*
X919209Y-179764D01*
X919864Y-181805D01*
Y-189972D01*
G01X930377Y-182097D02*
X937364D01*
X936709Y-180055D01*
X935617Y-178889D01*
X934089Y-178306D01*
X932560Y-178597D01*
X931250Y-179472D01*
X930377Y-181514D01*
X929940Y-183264D01*
Y-185014D01*
X930377Y-186764D01*
X931469Y-188514D01*
X932779Y-189680D01*
X934307Y-189972D01*
X935835Y-189389D01*
X937364Y-187639D01*
G01X948095Y-189972D02*
Y-178306D01*
G01Y-180639D02*
X949187Y-179472D01*
X950279Y-178597D01*
X951807Y-178306D01*
X952898Y-178597D01*
X954209Y-179472D01*
G01X994852Y-217472D02*
X993105Y-218055D01*
X991795Y-219514D01*
X990922Y-221263D01*
X990267Y-223597D01*
X990049Y-226222D01*
X990267Y-228847D01*
X990922Y-231181D01*
X991795Y-232931D01*
X993105Y-234389D01*
X994852Y-234972D01*
X996598Y-234389D01*
X997909Y-232931D01*
X998782Y-231181D01*
X999437Y-228847D01*
X999655Y-226222D01*
X999437Y-223597D01*
X998782Y-221263D01*
X997909Y-219514D01*
X996598Y-218055D01*
X994852Y-217472D01*
G01X1012352Y-234972D02*
X1013880Y-234680D01*
X1015627Y-233806D01*
X1016719Y-232348D01*
X1017155Y-230305D01*
X1016719Y-228264D01*
X1015409Y-226514D01*
X1013444Y-225639D01*
X1011260D01*
X1009950Y-225055D01*
X1008858Y-223597D01*
X1008422Y-221556D01*
X1009077Y-219514D01*
X1010605Y-218055D01*
X1012352Y-217472D01*
X1014098Y-218055D01*
X1015627Y-219514D01*
X1016282Y-221556D01*
X1015845Y-223597D01*
X1014754Y-225055D01*
X1013444Y-225639D01*
X1011260D01*
X1009295Y-226514D01*
X1007985Y-228264D01*
X1007549Y-230305D01*
X1007985Y-232348D01*
X1009077Y-233806D01*
X1010824Y-234680D01*
X1012352Y-234972D01*
G01X1025922Y-235555D02*
X1033782Y-217472D01*
G01X1043204Y-220389D02*
X1044514Y-218639D01*
X1046042Y-217764D01*
X1047789Y-217472D01*
X1049972Y-218055D01*
X1051500Y-219514D01*
X1051937Y-221263D01*
X1051719Y-223014D01*
X1050845Y-224472D01*
X1046479Y-227389D01*
X1044514Y-229430D01*
X1043204Y-232348D01*
X1042767Y-234972D01*
X1051937D01*
G01X1060049Y-232348D02*
X1061358Y-233806D01*
X1062887Y-234680D01*
X1064852Y-234972D01*
X1066817Y-234389D01*
X1068345Y-233222D01*
X1069437Y-231181D01*
X1069655Y-228847D01*
X1069219Y-226514D01*
X1068127Y-225055D01*
X1066598Y-223889D01*
X1065070Y-223597D01*
X1063542Y-223889D01*
X1061577Y-225055D01*
X1062232Y-217472D01*
X1068127D01*
G01X1078422Y-235555D02*
X1086282Y-217472D01*
G01X1095704Y-220389D02*
X1097014Y-218639D01*
X1098542Y-217764D01*
X1100289Y-217472D01*
X1102472Y-218055D01*
X1104000Y-219514D01*
X1104437Y-221263D01*
X1104219Y-223014D01*
X1103345Y-224472D01*
X1098979Y-227389D01*
X1097014Y-229430D01*
X1095704Y-232348D01*
X1095267Y-234972D01*
X1104437D01*
G01X1117352Y-217472D02*
X1115605Y-218055D01*
X1114295Y-219514D01*
X1113422Y-221263D01*
X1112767Y-223597D01*
X1112549Y-226222D01*
X1112767Y-228847D01*
X1113422Y-231181D01*
X1114295Y-232931D01*
X1115605Y-234389D01*
X1117352Y-234972D01*
X1119098Y-234389D01*
X1120409Y-232931D01*
X1121282Y-231181D01*
X1121937Y-228847D01*
X1122155Y-226222D01*
X1121937Y-223597D01*
X1121282Y-221263D01*
X1120409Y-219514D01*
X1119098Y-218055D01*
X1117352Y-217472D01*
G01X1134852Y-234972D02*
Y-217472D01*
X1132232Y-220972D01*
G01Y-234972D02*
X1137472D01*
G01X1148204Y-227681D02*
X1149732Y-225639D01*
X1151042Y-224472D01*
X1152789Y-223889D01*
X1154317Y-224472D01*
X1155409Y-225639D01*
X1156282Y-227389D01*
X1156500Y-229430D01*
X1156282Y-231181D01*
X1155409Y-232931D01*
X1154098Y-234389D01*
X1152570Y-234972D01*
X1150824Y-234389D01*
X1149295Y-232639D01*
X1148422Y-230014D01*
X1148204Y-227097D01*
X1148640Y-223306D01*
X1149295Y-221263D01*
X1150387Y-219222D01*
X1151915Y-217764D01*
X1153444Y-217472D01*
X1154972Y-218055D01*
X1156064Y-219514D01*
G01X1042549Y-189972D02*
Y-172472D01*
X1046915D01*
X1048662Y-173347D01*
X1049972Y-174514D01*
X1051064Y-176263D01*
X1051937Y-178306D01*
X1052155Y-181222D01*
X1051937Y-184139D01*
X1051064Y-186181D01*
X1049972Y-187931D01*
X1048662Y-189097D01*
X1046915Y-189972D01*
X1042549D01*
G01X1068782D02*
Y-178306D01*
G01Y-180347D02*
X1067909Y-179181D01*
X1066598Y-178597D01*
X1065070Y-178306D01*
X1063542Y-178889D01*
X1062232Y-180055D01*
X1061358Y-181805D01*
X1060922Y-184139D01*
X1061358Y-186472D01*
X1062232Y-188222D01*
X1063542Y-189389D01*
X1065070Y-189972D01*
X1066598Y-189680D01*
X1067909Y-188806D01*
X1068782Y-187639D01*
G01X1082352Y-172472D02*
Y-189972D01*
G01X1079295Y-178306D02*
X1085409D01*
G01X1096577Y-182097D02*
X1103564D01*
X1102909Y-180055D01*
X1101817Y-178889D01*
X1100289Y-178306D01*
X1098760Y-178597D01*
X1097450Y-179472D01*
X1096577Y-181514D01*
X1096140Y-183264D01*
Y-185014D01*
X1096577Y-186764D01*
X1097669Y-188514D01*
X1098979Y-189680D01*
X1100507Y-189972D01*
X1102035Y-189389D01*
X1103564Y-187639D01*
M02*
